FILE_TYPE = MACRO_DRAWING;
SET COLOR_WIRE YELLOW;
SET COLOR_PROP ORANGE;
SET COLOR_DOT WHITE;
SET COLOR_ARC YELLOW;
SET COLOR_BODY GREEN;
SET COLOR_NOTE PURPLE;
SET PROP_DISPLAY VALUE;
SET PAGE_NUMBER P13;
FORCEADD GENOA_SP5..4
(-4600 3650);
FORCEPROP 1 LAST LOCATION U25
J 0
(-5245 6481);
DISPLAY 0.489362 (-5245 6481);
PAINT SKYBLUE (-5245 6481);
FORCEPROP 0 LAST $SEC 4
J 0
(-5225 6525);
DISPLAY 0.680851 (-5225 6525);
PAINT MONO (-5225 6525);
DISPLAY INVISIBLE (-5225 6525);
FORCEPROP 0 LAST CDS_SEC 4
J 0
(-5250 6475);
DISPLAY 1.021277 (-5250 6475);
DISPLAY INVISIBLE (-5250 6475);
FORCEPROP 0 LASTPIN (-5400 3025) $PN BC60
J 2
(-5410 3035);
DISPLAY 0.489362 (-5410 3035);
PAINT MONO (-5410 3035);
FORCEPROP 0 LASTPIN (-5400 2975) $PN BD60
J 2
(-5410 2985);
DISPLAY 0.489362 (-5410 2985);
PAINT MONO (-5410 2985);
FORCEPROP 0 LASTPIN (-5400 1875) $PN BF60
J 2
(-5410 1885);
DISPLAY 0.489362 (-5410 1885);
PAINT MONO (-5410 1885);
FORCEPROP 0 LASTPIN (-5400 1825) $PN BG60
J 2
(-5410 1835);
DISPLAY 0.489362 (-5410 1835);
PAINT MONO (-5410 1835);
FORCEPROP 0 LASTPIN (-5400 2175) $PN AT58
J 2
(-5410 2185);
DISPLAY 0.489362 (-5410 2185);
PAINT MONO (-5410 2185);
FORCEPROP 0 LASTPIN (-5400 2075) $PN AU59
J 2
(-5410 2085);
DISPLAY 0.489362 (-5410 2085);
PAINT MONO (-5410 2085);
FORCEPROP 0 LASTPIN (-5400 2875) $PN AV60
J 2
(-5410 2885);
DISPLAY 0.489362 (-5410 2885);
PAINT MONO (-5410 2885);
FORCEPROP 0 LASTPIN (-5400 2825) $PN AW59
J 2
(-5410 2835);
DISPLAY 0.489362 (-5410 2835);
PAINT MONO (-5410 2835);
FORCEPROP 0 LASTPIN (-5400 2725) $PN BN59
J 2
(-5410 2735);
DISPLAY 0.489362 (-5410 2735);
PAINT MONO (-5410 2735);
FORCEPROP 0 LASTPIN (-5400 1725) $PN AU60
J 2
(-5410 1735);
DISPLAY 0.489362 (-5410 1735);
PAINT MONO (-5410 1735);
FORCEPROP 0 LASTPIN (-5400 1675) $PN AV58
J 2
(-5410 1685);
DISPLAY 0.489362 (-5410 1685);
PAINT MONO (-5410 1685);
FORCEPROP 0 LASTPIN (-5400 1575) $PN BP58
J 2
(-5410 1585);
DISPLAY 0.489362 (-5410 1585);
PAINT MONO (-5410 1585);
FORCEPROP 0 LASTPIN (-5400 3875) $PN AW60
J 2
(-5410 3885);
DISPLAY 0.489362 (-5410 3885);
PAINT MONO (-5410 3885);
FORCEPROP 0 LASTPIN (-5400 3825) $PN AY60
J 2
(-5410 3835);
DISPLAY 0.489362 (-5410 3835);
PAINT MONO (-5410 3835);
FORCEPROP 0 LASTPIN (-5400 3775) $PN AY58
J 2
(-5410 3785);
DISPLAY 0.489362 (-5410 3785);
PAINT MONO (-5410 3785);
FORCEPROP 0 LASTPIN (-5400 3725) $PN BA59
J 2
(-5410 3735);
DISPLAY 0.489362 (-5410 3735);
PAINT MONO (-5410 3735);
FORCEPROP 0 LASTPIN (-5400 3675) $PN BA60
J 2
(-5410 3685);
DISPLAY 0.489362 (-5410 3685);
PAINT MONO (-5410 3685);
FORCEPROP 0 LASTPIN (-5400 3625) $PN BB60
J 2
(-5410 3635);
DISPLAY 0.489362 (-5410 3635);
PAINT MONO (-5410 3635);
FORCEPROP 0 LASTPIN (-5400 3575) $PN BB58
J 2
(-5410 3585);
DISPLAY 0.489362 (-5410 3585);
PAINT MONO (-5410 3585);
FORCEPROP 0 LASTPIN (-3800 2425) $PN AJ60
J 0
(-3790 2435);
DISPLAY 0.489362 (-3790 2435);
PAINT MONO (-3790 2435);
FORCEPROP 0 LASTPIN (-3800 2375) $PN AK58
J 0
(-3790 2385);
DISPLAY 0.489362 (-3790 2385);
PAINT MONO (-3790 2385);
FORCEPROP 0 LASTPIN (-3800 2325) $PN AK60
J 0
(-3790 2335);
DISPLAY 0.489362 (-3790 2335);
PAINT MONO (-3790 2335);
FORCEPROP 0 LASTPIN (-3800 2275) $PN AL59
J 0
(-3790 2285);
DISPLAY 0.489362 (-3790 2285);
PAINT MONO (-3790 2285);
FORCEPROP 0 LASTPIN (-3800 2225) $PN AN60
J 0
(-3790 2235);
DISPLAY 0.489362 (-3790 2235);
PAINT MONO (-3790 2235);
FORCEPROP 0 LASTPIN (-3800 2175) $PN AP58
J 0
(-3790 2185);
DISPLAY 0.489362 (-3790 2185);
PAINT MONO (-3790 2185);
FORCEPROP 0 LASTPIN (-3800 2125) $PN AP60
J 0
(-3790 2135);
DISPLAY 0.489362 (-3790 2135);
PAINT MONO (-3790 2135);
FORCEPROP 0 LASTPIN (-3800 2075) $PN AR59
J 0
(-3790 2085);
DISPLAY 0.489362 (-3790 2085);
PAINT MONO (-3790 2085);
FORCEPROP 0 LASTPIN (-3800 6025) $PN E60
J 0
(-3790 6035);
DISPLAY 0.489362 (-3790 6035);
PAINT MONO (-3790 6035);
FORCEPROP 0 LASTPIN (-3800 5975) $PN F58
J 0
(-3790 5985);
DISPLAY 0.489362 (-3790 5985);
PAINT MONO (-3790 5985);
FORCEPROP 0 LASTPIN (-3800 5925) $PN F60
J 0
(-3790 5935);
DISPLAY 0.489362 (-3790 5935);
PAINT MONO (-3790 5935);
FORCEPROP 0 LASTPIN (-3800 5875) $PN G59
J 0
(-3790 5885);
DISPLAY 0.489362 (-3790 5885);
PAINT MONO (-3790 5885);
FORCEPROP 0 LASTPIN (-3800 5825) $PN J60
J 0
(-3790 5835);
DISPLAY 0.489362 (-3790 5835);
PAINT MONO (-3790 5835);
FORCEPROP 0 LASTPIN (-3800 5775) $PN K58
J 0
(-3790 5785);
DISPLAY 0.489362 (-3790 5785);
PAINT MONO (-3790 5785);
FORCEPROP 0 LASTPIN (-3800 5725) $PN K60
J 0
(-3790 5735);
DISPLAY 0.489362 (-3790 5735);
PAINT MONO (-3790 5735);
FORCEPROP 0 LASTPIN (-3800 5675) $PN L59
J 0
(-3790 5685);
DISPLAY 0.489362 (-3790 5685);
PAINT MONO (-3790 5685);
FORCEPROP 0 LASTPIN (-3800 5575) $PN L60
J 0
(-3790 5585);
DISPLAY 0.489362 (-3790 5585);
PAINT MONO (-3790 5585);
FORCEPROP 0 LASTPIN (-3800 5525) $PN M58
J 0
(-3790 5535);
DISPLAY 0.489362 (-3790 5535);
PAINT MONO (-3790 5535);
FORCEPROP 0 LASTPIN (-3800 5475) $PN M60
J 0
(-3790 5485);
DISPLAY 0.489362 (-3790 5485);
PAINT MONO (-3790 5485);
FORCEPROP 0 LASTPIN (-3800 5425) $PN N59
J 0
(-3790 5435);
DISPLAY 0.489362 (-3790 5435);
PAINT MONO (-3790 5435);
FORCEPROP 0 LASTPIN (-3800 5375) $PN R60
J 0
(-3790 5385);
DISPLAY 0.489362 (-3790 5385);
PAINT MONO (-3790 5385);
FORCEPROP 0 LASTPIN (-3800 5325) $PN T58
J 0
(-3790 5335);
DISPLAY 0.489362 (-3790 5335);
PAINT MONO (-3790 5335);
FORCEPROP 0 LASTPIN (-3800 5275) $PN T60
J 0
(-3790 5285);
DISPLAY 0.489362 (-3790 5285);
PAINT MONO (-3790 5285);
FORCEPROP 0 LASTPIN (-3800 5225) $PN U59
J 0
(-3790 5235);
DISPLAY 0.489362 (-3790 5235);
PAINT MONO (-3790 5235);
FORCEPROP 0 LASTPIN (-3800 5125) $PN U60
J 0
(-3790 5135);
DISPLAY 0.489362 (-3790 5135);
PAINT MONO (-3790 5135);
FORCEPROP 0 LASTPIN (-3800 5075) $PN V58
J 0
(-3790 5085);
DISPLAY 0.489362 (-3790 5085);
PAINT MONO (-3790 5085);
FORCEPROP 0 LASTPIN (-3800 5025) $PN V60
J 0
(-3790 5035);
DISPLAY 0.489362 (-3790 5035);
PAINT MONO (-3790 5035);
FORCEPROP 0 LASTPIN (-3800 4975) $PN W59
J 0
(-3790 4985);
DISPLAY 0.489362 (-3790 4985);
PAINT MONO (-3790 4985);
FORCEPROP 0 LASTPIN (-3800 4925) $PN AA60
J 0
(-3790 4935);
DISPLAY 0.489362 (-3790 4935);
PAINT MONO (-3790 4935);
FORCEPROP 0 LASTPIN (-3800 4875) $PN AB58
J 0
(-3790 4885);
DISPLAY 0.489362 (-3790 4885);
PAINT MONO (-3790 4885);
FORCEPROP 0 LASTPIN (-3800 4825) $PN AB60
J 0
(-3790 4835);
DISPLAY 0.489362 (-3790 4835);
PAINT MONO (-3790 4835);
FORCEPROP 0 LASTPIN (-3800 4775) $PN AC59
J 0
(-3790 4785);
DISPLAY 0.489362 (-3790 4785);
PAINT MONO (-3790 4785);
FORCEPROP 0 LASTPIN (-3800 4675) $PN AC60
J 0
(-3790 4685);
DISPLAY 0.489362 (-3790 4685);
PAINT MONO (-3790 4685);
FORCEPROP 0 LASTPIN (-3800 4625) $PN AD58
J 0
(-3790 4635);
DISPLAY 0.489362 (-3790 4635);
PAINT MONO (-3790 4635);
FORCEPROP 0 LASTPIN (-3800 4575) $PN AD60
J 0
(-3790 4585);
DISPLAY 0.489362 (-3790 4585);
PAINT MONO (-3790 4585);
FORCEPROP 0 LASTPIN (-3800 4525) $PN AE59
J 0
(-3790 4535);
DISPLAY 0.489362 (-3790 4535);
PAINT MONO (-3790 4535);
FORCEPROP 0 LASTPIN (-3800 4475) $PN AG60
J 0
(-3790 4485);
DISPLAY 0.489362 (-3790 4485);
PAINT MONO (-3790 4485);
FORCEPROP 0 LASTPIN (-3800 4425) $PN AH58
J 0
(-3790 4435);
DISPLAY 0.489362 (-3790 4435);
PAINT MONO (-3790 4435);
FORCEPROP 0 LASTPIN (-3800 4375) $PN AH60
J 0
(-3790 4385);
DISPLAY 0.489362 (-3790 4385);
PAINT MONO (-3790 4385);
FORCEPROP 0 LASTPIN (-3800 4325) $PN AJ59
J 0
(-3790 4335);
DISPLAY 0.489362 (-3790 4335);
PAINT MONO (-3790 4335);
FORCEPROP 0 LASTPIN (-5400 6025) $PN G60
J 2
(-5410 6035);
DISPLAY 0.489362 (-5410 6035);
PAINT MONO (-5410 6035);
FORCEPROP 0 LASTPIN (-5400 5925) $PN N60
J 2
(-5410 5935);
DISPLAY 0.489362 (-5410 5935);
PAINT MONO (-5410 5935);
FORCEPROP 0 LASTPIN (-5400 5825) $PN W60
J 2
(-5410 5835);
DISPLAY 0.489362 (-5410 5835);
PAINT MONO (-5410 5835);
FORCEPROP 0 LASTPIN (-5400 5725) $PN AE60
J 2
(-5410 5735);
DISPLAY 0.489362 (-5410 5735);
PAINT MONO (-5410 5735);
FORCEPROP 0 LASTPIN (-5400 5625) $PN AL60
J 2
(-5410 5635);
DISPLAY 0.489362 (-5410 5635);
PAINT MONO (-5410 5635);
FORCEPROP 0 LASTPIN (-5400 5525) $PN J59
J 2
(-5410 5535);
DISPLAY 0.489362 (-5410 5535);
PAINT MONO (-5410 5535);
FORCEPROP 0 LASTPIN (-5400 5425) $PN R59
J 2
(-5410 5435);
DISPLAY 0.489362 (-5410 5435);
PAINT MONO (-5410 5435);
FORCEPROP 0 LASTPIN (-5400 5325) $PN AA59
J 2
(-5410 5335);
DISPLAY 0.489362 (-5410 5335);
PAINT MONO (-5410 5335);
FORCEPROP 0 LASTPIN (-5400 5225) $PN AG59
J 2
(-5410 5235);
DISPLAY 0.489362 (-5410 5235);
PAINT MONO (-5410 5235);
FORCEPROP 0 LASTPIN (-5400 5125) $PN AN59
J 2
(-5410 5135);
DISPLAY 0.489362 (-5410 5135);
PAINT MONO (-5410 5135);
FORCEPROP 0 LASTPIN (-5400 5975) $PN H60
J 2
(-5410 5985);
DISPLAY 0.489362 (-5410 5985);
PAINT MONO (-5410 5985);
FORCEPROP 0 LASTPIN (-5400 5875) $PN P60
J 2
(-5410 5885);
DISPLAY 0.489362 (-5410 5885);
PAINT MONO (-5410 5885);
FORCEPROP 0 LASTPIN (-5400 5775) $PN Y60
J 2
(-5410 5785);
DISPLAY 0.489362 (-5410 5785);
PAINT MONO (-5410 5785);
FORCEPROP 0 LASTPIN (-5400 5675) $PN AF60
J 2
(-5410 5685);
DISPLAY 0.489362 (-5410 5685);
PAINT MONO (-5410 5685);
FORCEPROP 0 LASTPIN (-5400 5575) $PN AM60
J 2
(-5410 5585);
DISPLAY 0.489362 (-5410 5585);
PAINT MONO (-5410 5585);
FORCEPROP 0 LASTPIN (-5400 5475) $PN H58
J 2
(-5410 5485);
DISPLAY 0.489362 (-5410 5485);
PAINT MONO (-5410 5485);
FORCEPROP 0 LASTPIN (-5400 5375) $PN P58
J 2
(-5410 5385);
DISPLAY 0.489362 (-5410 5385);
PAINT MONO (-5410 5385);
FORCEPROP 0 LASTPIN (-5400 5275) $PN Y58
J 2
(-5410 5285);
DISPLAY 0.489362 (-5410 5285);
PAINT MONO (-5410 5285);
FORCEPROP 0 LASTPIN (-5400 5175) $PN AF58
J 2
(-5410 5185);
DISPLAY 0.489362 (-5410 5185);
PAINT MONO (-5410 5185);
FORCEPROP 0 LASTPIN (-5400 5075) $PN AM58
J 2
(-5410 5085);
DISPLAY 0.489362 (-5410 5085);
PAINT MONO (-5410 5085);
FORCEPROP 0 LASTPIN (-5400 2625) $PN BC59
J 2
(-5410 2635);
DISPLAY 0.489362 (-5410 2635);
PAINT MONO (-5410 2635);
FORCEPROP 0 LASTPIN (-5400 2525) $PN BM58
J 2
(-5410 2535);
DISPLAY 0.489362 (-5410 2535);
PAINT MONO (-5410 2535);
FORCEPROP 0 LASTPIN (-5400 2475) $PN BN60
J 2
(-5410 2485);
DISPLAY 0.489362 (-5410 2485);
PAINT MONO (-5410 2485);
FORCEPROP 0 LASTPIN (-5400 2375) $PN BP60
J 2
(-5410 2385);
DISPLAY 0.489362 (-5410 2385);
PAINT MONO (-5410 2385);
FORCEPROP 0 LASTPIN (-5400 1475) $PN BL59
J 2
(-5410 1485);
DISPLAY 0.489362 (-5410 1485);
PAINT MONO (-5410 1485);
FORCEPROP 0 LASTPIN (-5400 1425) $PN BM60
J 2
(-5410 1435);
DISPLAY 0.489362 (-5410 1435);
PAINT MONO (-5410 1435);
FORCEPROP 0 LASTPIN (-5400 1325) $PN BR60
J 2
(-5410 1335);
DISPLAY 0.489362 (-5410 1335);
PAINT MONO (-5410 1335);
FORCEPROP 0 LASTPIN (-5400 3475) $PN BG59
J 2
(-5410 3485);
DISPLAY 0.489362 (-5410 3485);
PAINT MONO (-5410 3485);
FORCEPROP 0 LASTPIN (-5400 3425) $PN BH58
J 2
(-5410 3435);
DISPLAY 0.489362 (-5410 3435);
PAINT MONO (-5410 3435);
FORCEPROP 0 LASTPIN (-5400 3375) $PN BH60
J 2
(-5410 3385);
DISPLAY 0.489362 (-5410 3385);
PAINT MONO (-5410 3385);
FORCEPROP 0 LASTPIN (-5400 3325) $PN BJ60
J 2
(-5410 3335);
DISPLAY 0.489362 (-5410 3335);
PAINT MONO (-5410 3335);
FORCEPROP 0 LASTPIN (-5400 3275) $PN BJ59
J 2
(-5410 3285);
DISPLAY 0.489362 (-5410 3285);
PAINT MONO (-5410 3285);
FORCEPROP 0 LASTPIN (-5400 3225) $PN BK58
J 2
(-5410 3235);
DISPLAY 0.489362 (-5410 3235);
PAINT MONO (-5410 3235);
FORCEPROP 0 LASTPIN (-5400 3175) $PN BK60
J 2
(-5410 3185);
DISPLAY 0.489362 (-5410 3185);
PAINT MONO (-5410 3185);
FORCEPROP 0 LASTPIN (-3800 1975) $PN BY60
J 0
(-3790 1985);
DISPLAY 0.489362 (-3790 1985);
PAINT MONO (-3790 1985);
FORCEPROP 0 LASTPIN (-3800 1925) $PN CA59
J 0
(-3790 1935);
DISPLAY 0.489362 (-3790 1935);
PAINT MONO (-3790 1935);
FORCEPROP 0 LASTPIN (-3800 1875) $PN CA60
J 0
(-3790 1885);
DISPLAY 0.489362 (-3790 1885);
PAINT MONO (-3790 1885);
FORCEPROP 0 LASTPIN (-3800 1825) $PN CB58
J 0
(-3790 1835);
DISPLAY 0.489362 (-3790 1835);
PAINT MONO (-3790 1835);
FORCEPROP 0 LASTPIN (-3800 1775) $PN BT60
J 0
(-3790 1785);
DISPLAY 0.489362 (-3790 1785);
PAINT MONO (-3790 1785);
FORCEPROP 0 LASTPIN (-3800 1725) $PN BU59
J 0
(-3790 1735);
DISPLAY 0.489362 (-3790 1735);
PAINT MONO (-3790 1735);
FORCEPROP 0 LASTPIN (-3800 1675) $PN BU60
J 0
(-3790 1685);
DISPLAY 0.489362 (-3790 1685);
PAINT MONO (-3790 1685);
FORCEPROP 0 LASTPIN (-3800 1625) $PN BV58
J 0
(-3790 1635);
DISPLAY 0.489362 (-3790 1635);
PAINT MONO (-3790 1635);
FORCEPROP 0 LASTPIN (-3800 4225) $PN CB60
J 0
(-3790 4235);
DISPLAY 0.489362 (-3790 4235);
PAINT MONO (-3790 4235);
FORCEPROP 0 LASTPIN (-3800 4175) $PN CC59
J 0
(-3790 4185);
DISPLAY 0.489362 (-3790 4185);
PAINT MONO (-3790 4185);
FORCEPROP 0 LASTPIN (-3800 4125) $PN CC60
J 0
(-3790 4135);
DISPLAY 0.489362 (-3790 4135);
PAINT MONO (-3790 4135);
FORCEPROP 0 LASTPIN (-3800 4075) $PN CD58
J 0
(-3790 4085);
DISPLAY 0.489362 (-3790 4085);
PAINT MONO (-3790 4085);
FORCEPROP 0 LASTPIN (-3800 4025) $PN CF60
J 0
(-3790 4035);
DISPLAY 0.489362 (-3790 4035);
PAINT MONO (-3790 4035);
FORCEPROP 0 LASTPIN (-3800 3975) $PN CG59
J 0
(-3790 3985);
DISPLAY 0.489362 (-3790 3985);
PAINT MONO (-3790 3985);
FORCEPROP 0 LASTPIN (-3800 3925) $PN CG60
J 0
(-3790 3935);
DISPLAY 0.489362 (-3790 3935);
PAINT MONO (-3790 3935);
FORCEPROP 0 LASTPIN (-3800 3875) $PN CH58
J 0
(-3790 3885);
DISPLAY 0.489362 (-3790 3885);
PAINT MONO (-3790 3885);
FORCEPROP 0 LASTPIN (-3800 3775) $PN CH60
J 0
(-3790 3785);
DISPLAY 0.489362 (-3790 3785);
PAINT MONO (-3790 3785);
FORCEPROP 0 LASTPIN (-3800 3725) $PN CJ59
J 0
(-3790 3735);
DISPLAY 0.489362 (-3790 3735);
PAINT MONO (-3790 3735);
FORCEPROP 0 LASTPIN (-3800 3675) $PN CJ60
J 0
(-3790 3685);
DISPLAY 0.489362 (-3790 3685);
PAINT MONO (-3790 3685);
FORCEPROP 0 LASTPIN (-3800 3625) $PN CK58
J 0
(-3790 3635);
DISPLAY 0.489362 (-3790 3635);
PAINT MONO (-3790 3635);
FORCEPROP 0 LASTPIN (-3800 3575) $PN CM60
J 0
(-3790 3585);
DISPLAY 0.489362 (-3790 3585);
PAINT MONO (-3790 3585);
FORCEPROP 0 LASTPIN (-3800 3525) $PN CN59
J 0
(-3790 3535);
DISPLAY 0.489362 (-3790 3535);
PAINT MONO (-3790 3535);
FORCEPROP 0 LASTPIN (-3800 3475) $PN CN60
J 0
(-3790 3485);
DISPLAY 0.489362 (-3790 3485);
PAINT MONO (-3790 3485);
FORCEPROP 0 LASTPIN (-3800 3425) $PN CP58
J 0
(-3790 3435);
DISPLAY 0.489362 (-3790 3435);
PAINT MONO (-3790 3435);
FORCEPROP 0 LASTPIN (-3800 3325) $PN CP60
J 0
(-3790 3335);
DISPLAY 0.489362 (-3790 3335);
PAINT MONO (-3790 3335);
FORCEPROP 0 LASTPIN (-3800 3275) $PN CR59
J 0
(-3790 3285);
DISPLAY 0.489362 (-3790 3285);
PAINT MONO (-3790 3285);
FORCEPROP 0 LASTPIN (-3800 3225) $PN CR60
J 0
(-3790 3235);
DISPLAY 0.489362 (-3790 3235);
PAINT MONO (-3790 3235);
FORCEPROP 0 LASTPIN (-3800 3175) $PN CT58
J 0
(-3790 3185);
DISPLAY 0.489362 (-3790 3185);
PAINT MONO (-3790 3185);
FORCEPROP 0 LASTPIN (-3800 3125) $PN CV60
J 0
(-3790 3135);
DISPLAY 0.489362 (-3790 3135);
PAINT MONO (-3790 3135);
FORCEPROP 0 LASTPIN (-3800 3075) $PN CW59
J 0
(-3790 3085);
DISPLAY 0.489362 (-3790 3085);
PAINT MONO (-3790 3085);
FORCEPROP 0 LASTPIN (-3800 3025) $PN CW60
J 0
(-3790 3035);
DISPLAY 0.489362 (-3790 3035);
PAINT MONO (-3790 3035);
FORCEPROP 0 LASTPIN (-3800 2975) $PN CY58
J 0
(-3790 2985);
DISPLAY 0.489362 (-3790 2985);
PAINT MONO (-3790 2985);
FORCEPROP 0 LASTPIN (-3800 2875) $PN CY60
J 0
(-3790 2885);
DISPLAY 0.489362 (-3790 2885);
PAINT MONO (-3790 2885);
FORCEPROP 0 LASTPIN (-3800 2825) $PN DA59
J 0
(-3790 2835);
DISPLAY 0.489362 (-3790 2835);
PAINT MONO (-3790 2835);
FORCEPROP 0 LASTPIN (-3800 2775) $PN DA60
J 0
(-3790 2785);
DISPLAY 0.489362 (-3790 2785);
PAINT MONO (-3790 2785);
FORCEPROP 0 LASTPIN (-3800 2725) $PN DB58
J 0
(-3790 2735);
DISPLAY 0.489362 (-3790 2735);
PAINT MONO (-3790 2735);
FORCEPROP 0 LASTPIN (-3800 2675) $PN DD60
J 0
(-3790 2685);
DISPLAY 0.489362 (-3790 2685);
PAINT MONO (-3790 2685);
FORCEPROP 0 LASTPIN (-3800 2625) $PN DE59
J 0
(-3790 2635);
DISPLAY 0.489362 (-3790 2635);
PAINT MONO (-3790 2635);
FORCEPROP 0 LASTPIN (-3800 2575) $PN DE60
J 0
(-3790 2585);
DISPLAY 0.489362 (-3790 2585);
PAINT MONO (-3790 2585);
FORCEPROP 0 LASTPIN (-3800 2525) $PN DF60
J 0
(-3790 2535);
DISPLAY 0.489362 (-3790 2535);
PAINT MONO (-3790 2535);
FORCEPROP 0 LASTPIN (-5400 4975) $PN CD60
J 2
(-5410 4985);
DISPLAY 0.489362 (-5410 4985);
PAINT MONO (-5410 4985);
FORCEPROP 0 LASTPIN (-5400 4875) $PN CK60
J 2
(-5410 4885);
DISPLAY 0.489362 (-5410 4885);
PAINT MONO (-5410 4885);
FORCEPROP 0 LASTPIN (-5400 4775) $PN CT60
J 2
(-5410 4785);
DISPLAY 0.489362 (-5410 4785);
PAINT MONO (-5410 4785);
FORCEPROP 0 LASTPIN (-5400 4675) $PN DB60
J 2
(-5410 4685);
DISPLAY 0.489362 (-5410 4685);
PAINT MONO (-5410 4685);
FORCEPROP 0 LASTPIN (-5400 4575) $PN BY58
J 2
(-5410 4585);
DISPLAY 0.489362 (-5410 4585);
PAINT MONO (-5410 4585);
FORCEPROP 0 LASTPIN (-5400 4475) $PN CF58
J 2
(-5410 4485);
DISPLAY 0.489362 (-5410 4485);
PAINT MONO (-5410 4485);
FORCEPROP 0 LASTPIN (-5400 4375) $PN CM58
J 2
(-5410 4385);
DISPLAY 0.489362 (-5410 4385);
PAINT MONO (-5410 4385);
FORCEPROP 0 LASTPIN (-5400 4275) $PN CV58
J 2
(-5410 4285);
DISPLAY 0.489362 (-5410 4285);
PAINT MONO (-5410 4285);
FORCEPROP 0 LASTPIN (-5400 4175) $PN DD58
J 2
(-5410 4185);
DISPLAY 0.489362 (-5410 4185);
PAINT MONO (-5410 4185);
FORCEPROP 0 LASTPIN (-5400 4075) $PN BV60
J 2
(-5410 4085);
DISPLAY 0.489362 (-5410 4085);
PAINT MONO (-5410 4085);
FORCEPROP 0 LASTPIN (-5400 4925) $PN CE60
J 2
(-5410 4935);
DISPLAY 0.489362 (-5410 4935);
PAINT MONO (-5410 4935);
FORCEPROP 0 LASTPIN (-5400 4825) $PN CL60
J 2
(-5410 4835);
DISPLAY 0.489362 (-5410 4835);
PAINT MONO (-5410 4835);
FORCEPROP 0 LASTPIN (-5400 4725) $PN CU60
J 2
(-5410 4735);
DISPLAY 0.489362 (-5410 4735);
PAINT MONO (-5410 4735);
FORCEPROP 0 LASTPIN (-5400 4625) $PN DC60
J 2
(-5410 4635);
DISPLAY 0.489362 (-5410 4635);
PAINT MONO (-5410 4635);
FORCEPROP 0 LASTPIN (-5400 4525) $PN BW59
J 2
(-5410 4535);
DISPLAY 0.489362 (-5410 4535);
PAINT MONO (-5410 4535);
FORCEPROP 0 LASTPIN (-5400 4425) $PN CE59
J 2
(-5410 4435);
DISPLAY 0.489362 (-5410 4435);
PAINT MONO (-5410 4435);
FORCEPROP 0 LASTPIN (-5400 4325) $PN CL59
J 2
(-5410 4335);
DISPLAY 0.489362 (-5410 4335);
PAINT MONO (-5410 4335);
FORCEPROP 0 LASTPIN (-5400 4225) $PN CU59
J 2
(-5410 4235);
DISPLAY 0.489362 (-5410 4235);
PAINT MONO (-5410 4235);
FORCEPROP 0 LASTPIN (-5400 4125) $PN DC59
J 2
(-5410 4135);
DISPLAY 0.489362 (-5410 4135);
PAINT MONO (-5410 4135);
FORCEPROP 0 LASTPIN (-5400 4025) $PN BW60
J 2
(-5410 4035);
DISPLAY 0.489362 (-5410 4035);
PAINT MONO (-5410 4035);
FORCEPROP 0 LASTPIN (-5400 2275) $PN BL60
J 2
(-5410 2285);
DISPLAY 0.489362 (-5410 2285);
PAINT MONO (-5410 2285);
FORCEPROP 0 LASTPIN (-5400 1225) $PN BF58
J 2
(-5410 1235);
DISPLAY 0.489362 (-5410 1235);
PAINT MONO (-5410 1235);
FORCEPROP 2 LAST VALUE SOCKET6096_13568-001
J 0
(-5250 6305);
DISPLAY 0.489362 (-5250 6305);
PAINT SKYBLUE (-5250 6305);
FORCEPROP 1 LAST MATERIAL IO
J 0
(-5245 6207);
DISPLAY 0.489362 (-5245 6207);
PAINT SKYBLUE (-5245 6207);
FORCEPROP 2 LAST PART_TYPE SMLF
J 0
(-5250 6405);
DISPLAY 1.021277 (-5250 6405);
FORCEPROP 1 LAST NEEDS_NO_SIZE TRUE
J 0
(-4600 3650);
DISPLAY 0.723404 (-4600 3650);
PAINT GREEN (-4600 3650);
DISPLAY INVISIBLE (-4600 3650);
FORCEPROP 1 LAST CDS_LMAN_SYM_OUTLINE -650,2525,650,-2525
J 0
(-4600 3650);
DISPLAY 0.468085 (-4600 3650);
PAINT GREEN (-4600 3650);
DISPLAY INVISIBLE (-4600 3650);
FORCEPROP 2 LAST CDS_LIB pure_quanta
J 0
(-4600 3650);
DISPLAY INVISIBLE (-4600 3650);
FORCEPROP 1 LAST PATH I159
J 0
(-4600 3650);
DISPLAY 0.723404 (-4600 3650);
PAINT GREEN (-4600 3650);
DISPLAY INVISIBLE (-4600 3650);
FORCEPROP 1 LAST PART_NUMBER DGA^6000030
J 0
(-5245 6334);
DISPLAY 0.489362 (-5245 6334);
PAINT SKYBLUE (-5245 6334);
DISPLAY INVISIBLE (-5245 6334);
FORCEADD OFFPAGE..3
(-2600 6050);
FORCEPROP 2 LAST $XR0 89 
J 0
(-2386 6050);
DISPLAY 0.638298 (-2386 6050);
PAINT MONO (-2386 6050);
FORCEPROP 2 LAST CDS_LIB mstr_standard
J 0
(-2600 6050);
DISPLAY 0.723404 (-2600 6050);
PAINT MONO (-2600 6050);
DISPLAY INVISIBLE (-2600 6050);
FORCEPROP 1 LAST OFFPAGE TRUE
J 0
(-2275 5925);
DISPLAY 0.872340 (-2275 5925);
PAINT GREEN (-2275 5925);
DISPLAY INVISIBLE (-2275 5925);
FORCEPROP 1 LAST COMMENT_BODY TRUE
J 0
(-2650 5950);
DISPLAY 0.872340 (-2650 5950);
PAINT GREEN (-2650 5950);
DISPLAY INVISIBLE (-2650 5950);
FORCEPROP 2 LAST PATH I160
J 0
(-2375 6100);
DISPLAY 1.021277 (-2375 6100);
DISPLAY INVISIBLE (-2375 6100);
FORCEADD OFFPAGE..3
(-2600 4250);
FORCEPROP 2 LAST $XR0 89 
J 0
(-2386 4250);
DISPLAY 0.638298 (-2386 4250);
PAINT MONO (-2386 4250);
FORCEPROP 2 LAST CDS_LIB mstr_standard
J 0
(-2600 4250);
DISPLAY 0.723404 (-2600 4250);
PAINT MONO (-2600 4250);
DISPLAY INVISIBLE (-2600 4250);
FORCEPROP 1 LAST OFFPAGE TRUE
J 0
(-2275 4125);
DISPLAY 0.872340 (-2275 4125);
PAINT GREEN (-2275 4125);
DISPLAY INVISIBLE (-2275 4125);
FORCEPROP 1 LAST COMMENT_BODY TRUE
J 0
(-2650 4150);
DISPLAY 0.872340 (-2650 4150);
PAINT GREEN (-2650 4150);
DISPLAY INVISIBLE (-2650 4150);
FORCEPROP 2 LAST PATH I161
J 0
(-2375 4300);
DISPLAY 1.021277 (-2375 4300);
DISPLAY INVISIBLE (-2375 4300);
FORCEADD TAP..1
(-3325 5925);
FORCEPROP 3 LASTPIN (-3375 5925) SIG_NAME M_D_CPU0_SA_DQ<2>
J 0
(-3365 5935);
DISPLAY 0.659574 (-3365 5935);
PAINT MONO (-3365 5935);
DISPLAY INVISIBLE (-3365 5935);
FORCEPROP 1 LASTPIN (-3375 5925) BN 2
J 0
(-3387 5933);
DISPLAY 0.489362 (-3387 5933);
PAINT GREEN (-3387 5933);
FORCEPROP 2 LAST CDS_LIB mstr_standard
J 0
(-3325 5925);
DISPLAY 0.723404 (-3325 5925);
PAINT MONO (-3325 5925);
DISPLAY INVISIBLE (-3325 5925);
FORCEPROP 1 LAST BODY_TYPE PLUMBING
J 0
(-3325 5975);
DISPLAY 0.872340 (-3325 5975);
PAINT GREEN (-3325 5975);
DISPLAY INVISIBLE (-3325 5975);
FORCEPROP 1 LAST HDL_TAP TRUE
J 0
(-3000 5800);
DISPLAY 0.872340 (-3000 5800);
DISPLAY INVISIBLE (-3000 5800);
FORCEPROP 1 LAST PATH I162
J 0
(-3327 5925);
DISPLAY 0.872340 (-3327 5925);
PAINT GREEN (-3327 5925);
DISPLAY INVISIBLE (-3327 5925);
FORCEADD TAP..1
(-3325 6025);
FORCEPROP 3 LASTPIN (-3375 6025) SIG_NAME M_D_CPU0_SA_DQ<0>
J 0
(-3365 6035);
DISPLAY 0.659574 (-3365 6035);
PAINT MONO (-3365 6035);
DISPLAY INVISIBLE (-3365 6035);
FORCEPROP 1 LASTPIN (-3375 6025) BN 0
J 0
(-3387 6033);
DISPLAY 0.489362 (-3387 6033);
PAINT GREEN (-3387 6033);
FORCEPROP 2 LAST CDS_LIB mstr_standard
J 0
(-3325 6025);
DISPLAY 0.723404 (-3325 6025);
PAINT MONO (-3325 6025);
DISPLAY INVISIBLE (-3325 6025);
FORCEPROP 1 LAST BODY_TYPE PLUMBING
J 0
(-3325 6075);
DISPLAY 0.872340 (-3325 6075);
PAINT GREEN (-3325 6075);
DISPLAY INVISIBLE (-3325 6075);
FORCEPROP 1 LAST HDL_TAP TRUE
J 0
(-3000 5900);
DISPLAY 0.872340 (-3000 5900);
DISPLAY INVISIBLE (-3000 5900);
FORCEPROP 1 LAST PATH I163
J 0
(-3327 6025);
DISPLAY 0.872340 (-3327 6025);
PAINT GREEN (-3327 6025);
DISPLAY INVISIBLE (-3327 6025);
FORCEADD TAP..1
(-3325 5975);
FORCEPROP 3 LASTPIN (-3375 5975) SIG_NAME M_D_CPU0_SA_DQ<1>
J 0
(-3365 5985);
DISPLAY 0.659574 (-3365 5985);
PAINT MONO (-3365 5985);
DISPLAY INVISIBLE (-3365 5985);
FORCEPROP 1 LASTPIN (-3375 5975) BN 1
J 0
(-3387 5983);
DISPLAY 0.489362 (-3387 5983);
PAINT GREEN (-3387 5983);
FORCEPROP 2 LAST CDS_LIB mstr_standard
J 0
(-3325 5975);
DISPLAY 0.723404 (-3325 5975);
PAINT MONO (-3325 5975);
DISPLAY INVISIBLE (-3325 5975);
FORCEPROP 1 LAST BODY_TYPE PLUMBING
J 0
(-3325 6025);
DISPLAY 0.872340 (-3325 6025);
PAINT GREEN (-3325 6025);
DISPLAY INVISIBLE (-3325 6025);
FORCEPROP 1 LAST HDL_TAP TRUE
J 0
(-3000 5850);
DISPLAY 0.872340 (-3000 5850);
DISPLAY INVISIBLE (-3000 5850);
FORCEPROP 1 LAST PATH I164
J 0
(-3327 5975);
DISPLAY 0.872340 (-3327 5975);
PAINT GREEN (-3327 5975);
DISPLAY INVISIBLE (-3327 5975);
FORCEADD TAP..1
(-3325 5775);
FORCEPROP 3 LASTPIN (-3375 5775) SIG_NAME M_D_CPU0_SA_DQ<5>
J 0
(-3365 5785);
DISPLAY 0.659574 (-3365 5785);
PAINT MONO (-3365 5785);
DISPLAY INVISIBLE (-3365 5785);
FORCEPROP 1 LASTPIN (-3375 5775) BN 5
J 0
(-3387 5783);
DISPLAY 0.489362 (-3387 5783);
PAINT GREEN (-3387 5783);
FORCEPROP 2 LAST CDS_LIB mstr_standard
J 0
(-3325 5775);
DISPLAY 0.723404 (-3325 5775);
PAINT MONO (-3325 5775);
DISPLAY INVISIBLE (-3325 5775);
FORCEPROP 1 LAST BODY_TYPE PLUMBING
J 0
(-3325 5825);
DISPLAY 0.872340 (-3325 5825);
PAINT GREEN (-3325 5825);
DISPLAY INVISIBLE (-3325 5825);
FORCEPROP 1 LAST HDL_TAP TRUE
J 0
(-3000 5650);
DISPLAY 0.872340 (-3000 5650);
DISPLAY INVISIBLE (-3000 5650);
FORCEPROP 1 LAST PATH I165
J 0
(-3327 5775);
DISPLAY 0.872340 (-3327 5775);
PAINT GREEN (-3327 5775);
DISPLAY INVISIBLE (-3327 5775);
FORCEADD TAP..1
(-3325 5875);
FORCEPROP 3 LASTPIN (-3375 5875) SIG_NAME M_D_CPU0_SA_DQ<3>
J 0
(-3365 5885);
DISPLAY 0.659574 (-3365 5885);
PAINT MONO (-3365 5885);
DISPLAY INVISIBLE (-3365 5885);
FORCEPROP 1 LASTPIN (-3375 5875) BN 3
J 0
(-3387 5883);
DISPLAY 0.489362 (-3387 5883);
PAINT GREEN (-3387 5883);
FORCEPROP 2 LAST CDS_LIB mstr_standard
J 0
(-3325 5875);
DISPLAY 0.723404 (-3325 5875);
PAINT MONO (-3325 5875);
DISPLAY INVISIBLE (-3325 5875);
FORCEPROP 1 LAST BODY_TYPE PLUMBING
J 0
(-3325 5925);
DISPLAY 0.872340 (-3325 5925);
PAINT GREEN (-3325 5925);
DISPLAY INVISIBLE (-3325 5925);
FORCEPROP 1 LAST HDL_TAP TRUE
J 0
(-3000 5750);
DISPLAY 0.872340 (-3000 5750);
DISPLAY INVISIBLE (-3000 5750);
FORCEPROP 1 LAST PATH I166
J 0
(-3327 5875);
DISPLAY 0.872340 (-3327 5875);
PAINT GREEN (-3327 5875);
DISPLAY INVISIBLE (-3327 5875);
FORCEADD TAP..1
(-3325 5825);
FORCEPROP 3 LASTPIN (-3375 5825) SIG_NAME M_D_CPU0_SA_DQ<4>
J 0
(-3365 5835);
DISPLAY 0.659574 (-3365 5835);
PAINT MONO (-3365 5835);
DISPLAY INVISIBLE (-3365 5835);
FORCEPROP 1 LASTPIN (-3375 5825) BN 4
J 0
(-3387 5833);
DISPLAY 0.489362 (-3387 5833);
PAINT GREEN (-3387 5833);
FORCEPROP 2 LAST CDS_LIB mstr_standard
J 0
(-3325 5825);
DISPLAY 0.723404 (-3325 5825);
PAINT MONO (-3325 5825);
DISPLAY INVISIBLE (-3325 5825);
FORCEPROP 1 LAST BODY_TYPE PLUMBING
J 0
(-3325 5875);
DISPLAY 0.872340 (-3325 5875);
PAINT GREEN (-3325 5875);
DISPLAY INVISIBLE (-3325 5875);
FORCEPROP 1 LAST HDL_TAP TRUE
J 0
(-3000 5700);
DISPLAY 0.872340 (-3000 5700);
DISPLAY INVISIBLE (-3000 5700);
FORCEPROP 1 LAST PATH I167
J 0
(-3327 5825);
DISPLAY 0.872340 (-3327 5825);
PAINT GREEN (-3327 5825);
DISPLAY INVISIBLE (-3327 5825);
FORCEADD TAP..1
(-3325 5725);
FORCEPROP 3 LASTPIN (-3375 5725) SIG_NAME M_D_CPU0_SA_DQ<6>
J 0
(-3365 5735);
DISPLAY 0.659574 (-3365 5735);
PAINT MONO (-3365 5735);
DISPLAY INVISIBLE (-3365 5735);
FORCEPROP 1 LASTPIN (-3375 5725) BN 6
J 0
(-3387 5733);
DISPLAY 0.489362 (-3387 5733);
PAINT GREEN (-3387 5733);
FORCEPROP 2 LAST CDS_LIB mstr_standard
J 0
(-3325 5725);
DISPLAY 0.723404 (-3325 5725);
PAINT MONO (-3325 5725);
DISPLAY INVISIBLE (-3325 5725);
FORCEPROP 1 LAST BODY_TYPE PLUMBING
J 0
(-3325 5775);
DISPLAY 0.872340 (-3325 5775);
PAINT GREEN (-3325 5775);
DISPLAY INVISIBLE (-3325 5775);
FORCEPROP 1 LAST HDL_TAP TRUE
J 0
(-3000 5600);
DISPLAY 0.872340 (-3000 5600);
DISPLAY INVISIBLE (-3000 5600);
FORCEPROP 1 LAST PATH I168
J 0
(-3327 5725);
DISPLAY 0.872340 (-3327 5725);
PAINT GREEN (-3327 5725);
DISPLAY INVISIBLE (-3327 5725);
FORCEADD TAP..1
(-3325 5675);
FORCEPROP 3 LASTPIN (-3375 5675) SIG_NAME M_D_CPU0_SA_DQ<7>
J 0
(-3365 5685);
DISPLAY 0.659574 (-3365 5685);
PAINT MONO (-3365 5685);
DISPLAY INVISIBLE (-3365 5685);
FORCEPROP 1 LASTPIN (-3375 5675) BN 7
J 0
(-3387 5683);
DISPLAY 0.489362 (-3387 5683);
PAINT GREEN (-3387 5683);
FORCEPROP 2 LAST CDS_LIB mstr_standard
J 0
(-3325 5675);
DISPLAY 0.723404 (-3325 5675);
PAINT MONO (-3325 5675);
DISPLAY INVISIBLE (-3325 5675);
FORCEPROP 1 LAST BODY_TYPE PLUMBING
J 0
(-3325 5725);
DISPLAY 0.872340 (-3325 5725);
PAINT GREEN (-3325 5725);
DISPLAY INVISIBLE (-3325 5725);
FORCEPROP 1 LAST HDL_TAP TRUE
J 0
(-3000 5550);
DISPLAY 0.872340 (-3000 5550);
DISPLAY INVISIBLE (-3000 5550);
FORCEPROP 1 LAST PATH I169
J 0
(-3327 5675);
DISPLAY 0.872340 (-3327 5675);
PAINT GREEN (-3327 5675);
DISPLAY INVISIBLE (-3327 5675);
FORCEADD TAP..1
(-3325 5525);
FORCEPROP 3 LASTPIN (-3375 5525) SIG_NAME M_D_CPU0_SA_DQ<9>
J 0
(-3365 5535);
DISPLAY 0.659574 (-3365 5535);
PAINT MONO (-3365 5535);
DISPLAY INVISIBLE (-3365 5535);
FORCEPROP 1 LASTPIN (-3375 5525) BN 9
J 0
(-3387 5533);
DISPLAY 0.489362 (-3387 5533);
PAINT GREEN (-3387 5533);
FORCEPROP 2 LAST CDS_LIB mstr_standard
J 0
(-3325 5525);
DISPLAY 0.723404 (-3325 5525);
PAINT MONO (-3325 5525);
DISPLAY INVISIBLE (-3325 5525);
FORCEPROP 1 LAST BODY_TYPE PLUMBING
J 0
(-3325 5575);
DISPLAY 0.872340 (-3325 5575);
PAINT GREEN (-3325 5575);
DISPLAY INVISIBLE (-3325 5575);
FORCEPROP 1 LAST HDL_TAP TRUE
J 0
(-3000 5400);
DISPLAY 0.872340 (-3000 5400);
DISPLAY INVISIBLE (-3000 5400);
FORCEPROP 1 LAST PATH I170
J 0
(-3327 5525);
DISPLAY 0.872340 (-3327 5525);
PAINT GREEN (-3327 5525);
DISPLAY INVISIBLE (-3327 5525);
FORCEADD TAP..1
(-3325 5575);
FORCEPROP 3 LASTPIN (-3375 5575) SIG_NAME M_D_CPU0_SA_DQ<8>
J 0
(-3365 5585);
DISPLAY 0.659574 (-3365 5585);
PAINT MONO (-3365 5585);
DISPLAY INVISIBLE (-3365 5585);
FORCEPROP 1 LASTPIN (-3375 5575) BN 8
J 0
(-3387 5583);
DISPLAY 0.489362 (-3387 5583);
PAINT GREEN (-3387 5583);
FORCEPROP 2 LAST CDS_LIB mstr_standard
J 0
(-3325 5575);
DISPLAY 0.723404 (-3325 5575);
PAINT MONO (-3325 5575);
DISPLAY INVISIBLE (-3325 5575);
FORCEPROP 1 LAST BODY_TYPE PLUMBING
J 0
(-3325 5625);
DISPLAY 0.872340 (-3325 5625);
PAINT GREEN (-3325 5625);
DISPLAY INVISIBLE (-3325 5625);
FORCEPROP 1 LAST HDL_TAP TRUE
J 0
(-3000 5450);
DISPLAY 0.872340 (-3000 5450);
DISPLAY INVISIBLE (-3000 5450);
FORCEPROP 1 LAST PATH I171
J 0
(-3327 5575);
DISPLAY 0.872340 (-3327 5575);
PAINT GREEN (-3327 5575);
DISPLAY INVISIBLE (-3327 5575);
FORCEADD TAP..1
(-3325 5475);
FORCEPROP 3 LASTPIN (-3375 5475) SIG_NAME M_D_CPU0_SA_DQ<10>
J 0
(-3365 5485);
DISPLAY 0.659574 (-3365 5485);
PAINT MONO (-3365 5485);
DISPLAY INVISIBLE (-3365 5485);
FORCEPROP 1 LASTPIN (-3375 5475) BN 10
J 0
(-3387 5483);
DISPLAY 0.489362 (-3387 5483);
PAINT GREEN (-3387 5483);
FORCEPROP 2 LAST CDS_LIB mstr_standard
J 0
(-3325 5475);
DISPLAY 0.723404 (-3325 5475);
PAINT MONO (-3325 5475);
DISPLAY INVISIBLE (-3325 5475);
FORCEPROP 1 LAST BODY_TYPE PLUMBING
J 0
(-3325 5525);
DISPLAY 0.872340 (-3325 5525);
PAINT GREEN (-3325 5525);
DISPLAY INVISIBLE (-3325 5525);
FORCEPROP 1 LAST HDL_TAP TRUE
J 0
(-3000 5350);
DISPLAY 0.872340 (-3000 5350);
DISPLAY INVISIBLE (-3000 5350);
FORCEPROP 1 LAST PATH I172
J 0
(-3327 5475);
DISPLAY 0.872340 (-3327 5475);
PAINT GREEN (-3327 5475);
DISPLAY INVISIBLE (-3327 5475);
FORCEADD TAP..1
(-3325 5425);
FORCEPROP 3 LASTPIN (-3375 5425) SIG_NAME M_D_CPU0_SA_DQ<11>
J 0
(-3365 5435);
DISPLAY 0.659574 (-3365 5435);
PAINT MONO (-3365 5435);
DISPLAY INVISIBLE (-3365 5435);
FORCEPROP 1 LASTPIN (-3375 5425) BN 11
J 0
(-3387 5433);
DISPLAY 0.489362 (-3387 5433);
PAINT GREEN (-3387 5433);
FORCEPROP 2 LAST CDS_LIB mstr_standard
J 0
(-3325 5425);
DISPLAY 0.723404 (-3325 5425);
PAINT MONO (-3325 5425);
DISPLAY INVISIBLE (-3325 5425);
FORCEPROP 1 LAST BODY_TYPE PLUMBING
J 0
(-3325 5475);
DISPLAY 0.872340 (-3325 5475);
PAINT GREEN (-3325 5475);
DISPLAY INVISIBLE (-3325 5475);
FORCEPROP 1 LAST HDL_TAP TRUE
J 0
(-3000 5300);
DISPLAY 0.872340 (-3000 5300);
DISPLAY INVISIBLE (-3000 5300);
FORCEPROP 1 LAST PATH I173
J 0
(-3327 5425);
DISPLAY 0.872340 (-3327 5425);
PAINT GREEN (-3327 5425);
DISPLAY INVISIBLE (-3327 5425);
FORCEADD TAP..1
(-3325 5275);
FORCEPROP 3 LASTPIN (-3375 5275) SIG_NAME M_D_CPU0_SA_DQ<14>
J 0
(-3365 5285);
DISPLAY 0.659574 (-3365 5285);
PAINT MONO (-3365 5285);
DISPLAY INVISIBLE (-3365 5285);
FORCEPROP 1 LASTPIN (-3375 5275) BN 14
J 0
(-3387 5283);
DISPLAY 0.489362 (-3387 5283);
PAINT GREEN (-3387 5283);
FORCEPROP 2 LAST CDS_LIB mstr_standard
J 0
(-3325 5275);
DISPLAY 0.723404 (-3325 5275);
PAINT MONO (-3325 5275);
DISPLAY INVISIBLE (-3325 5275);
FORCEPROP 1 LAST BODY_TYPE PLUMBING
J 0
(-3325 5325);
DISPLAY 0.872340 (-3325 5325);
PAINT GREEN (-3325 5325);
DISPLAY INVISIBLE (-3325 5325);
FORCEPROP 1 LAST HDL_TAP TRUE
J 0
(-3000 5150);
DISPLAY 0.872340 (-3000 5150);
DISPLAY INVISIBLE (-3000 5150);
FORCEPROP 1 LAST PATH I174
J 0
(-3327 5275);
DISPLAY 0.872340 (-3327 5275);
PAINT GREEN (-3327 5275);
DISPLAY INVISIBLE (-3327 5275);
FORCEADD TAP..1
(-3325 5375);
FORCEPROP 3 LASTPIN (-3375 5375) SIG_NAME M_D_CPU0_SA_DQ<12>
J 0
(-3365 5385);
DISPLAY 0.659574 (-3365 5385);
PAINT MONO (-3365 5385);
DISPLAY INVISIBLE (-3365 5385);
FORCEPROP 1 LASTPIN (-3375 5375) BN 12
J 0
(-3387 5383);
DISPLAY 0.489362 (-3387 5383);
PAINT GREEN (-3387 5383);
FORCEPROP 2 LAST CDS_LIB mstr_standard
J 0
(-3325 5375);
DISPLAY 0.723404 (-3325 5375);
PAINT MONO (-3325 5375);
DISPLAY INVISIBLE (-3325 5375);
FORCEPROP 1 LAST BODY_TYPE PLUMBING
J 0
(-3325 5425);
DISPLAY 0.872340 (-3325 5425);
PAINT GREEN (-3325 5425);
DISPLAY INVISIBLE (-3325 5425);
FORCEPROP 1 LAST HDL_TAP TRUE
J 0
(-3000 5250);
DISPLAY 0.872340 (-3000 5250);
DISPLAY INVISIBLE (-3000 5250);
FORCEPROP 1 LAST PATH I175
J 0
(-3327 5375);
DISPLAY 0.872340 (-3327 5375);
PAINT GREEN (-3327 5375);
DISPLAY INVISIBLE (-3327 5375);
FORCEADD TAP..1
(-3325 5325);
FORCEPROP 3 LASTPIN (-3375 5325) SIG_NAME M_D_CPU0_SA_DQ<13>
J 0
(-3365 5335);
DISPLAY 0.659574 (-3365 5335);
PAINT MONO (-3365 5335);
DISPLAY INVISIBLE (-3365 5335);
FORCEPROP 1 LASTPIN (-3375 5325) BN 13
J 0
(-3387 5333);
DISPLAY 0.489362 (-3387 5333);
PAINT GREEN (-3387 5333);
FORCEPROP 2 LAST CDS_LIB mstr_standard
J 0
(-3325 5325);
DISPLAY 0.723404 (-3325 5325);
PAINT MONO (-3325 5325);
DISPLAY INVISIBLE (-3325 5325);
FORCEPROP 1 LAST BODY_TYPE PLUMBING
J 0
(-3325 5375);
DISPLAY 0.872340 (-3325 5375);
PAINT GREEN (-3325 5375);
DISPLAY INVISIBLE (-3325 5375);
FORCEPROP 1 LAST HDL_TAP TRUE
J 0
(-3000 5200);
DISPLAY 0.872340 (-3000 5200);
DISPLAY INVISIBLE (-3000 5200);
FORCEPROP 1 LAST PATH I176
J 0
(-3327 5325);
DISPLAY 0.872340 (-3327 5325);
PAINT GREEN (-3327 5325);
DISPLAY INVISIBLE (-3327 5325);
FORCEADD TAP..1
(-3325 5225);
FORCEPROP 3 LASTPIN (-3375 5225) SIG_NAME M_D_CPU0_SA_DQ<15>
J 0
(-3365 5235);
DISPLAY 0.659574 (-3365 5235);
PAINT MONO (-3365 5235);
DISPLAY INVISIBLE (-3365 5235);
FORCEPROP 1 LASTPIN (-3375 5225) BN 15
J 0
(-3387 5233);
DISPLAY 0.489362 (-3387 5233);
PAINT GREEN (-3387 5233);
FORCEPROP 2 LAST CDS_LIB mstr_standard
J 0
(-3325 5225);
DISPLAY 0.723404 (-3325 5225);
PAINT MONO (-3325 5225);
DISPLAY INVISIBLE (-3325 5225);
FORCEPROP 1 LAST BODY_TYPE PLUMBING
J 0
(-3325 5275);
DISPLAY 0.872340 (-3325 5275);
PAINT GREEN (-3325 5275);
DISPLAY INVISIBLE (-3325 5275);
FORCEPROP 1 LAST HDL_TAP TRUE
J 0
(-3000 5100);
DISPLAY 0.872340 (-3000 5100);
DISPLAY INVISIBLE (-3000 5100);
FORCEPROP 1 LAST PATH I177
J 0
(-3327 5225);
DISPLAY 0.872340 (-3327 5225);
PAINT GREEN (-3327 5225);
DISPLAY INVISIBLE (-3327 5225);
FORCEADD TAP..1
(-3325 5125);
FORCEPROP 3 LASTPIN (-3375 5125) SIG_NAME M_D_CPU0_SA_DQ<16>
J 0
(-3365 5135);
DISPLAY 0.659574 (-3365 5135);
PAINT MONO (-3365 5135);
DISPLAY INVISIBLE (-3365 5135);
FORCEPROP 1 LASTPIN (-3375 5125) BN 16
J 0
(-3387 5133);
DISPLAY 0.489362 (-3387 5133);
PAINT GREEN (-3387 5133);
FORCEPROP 2 LAST CDS_LIB mstr_standard
J 0
(-3325 5125);
DISPLAY 0.723404 (-3325 5125);
PAINT MONO (-3325 5125);
DISPLAY INVISIBLE (-3325 5125);
FORCEPROP 1 LAST BODY_TYPE PLUMBING
J 0
(-3325 5175);
DISPLAY 0.872340 (-3325 5175);
PAINT GREEN (-3325 5175);
DISPLAY INVISIBLE (-3325 5175);
FORCEPROP 1 LAST HDL_TAP TRUE
J 0
(-3000 5000);
DISPLAY 0.872340 (-3000 5000);
DISPLAY INVISIBLE (-3000 5000);
FORCEPROP 1 LAST PATH I178
J 0
(-3327 5125);
DISPLAY 0.872340 (-3327 5125);
PAINT GREEN (-3327 5125);
DISPLAY INVISIBLE (-3327 5125);
FORCEADD TAP..1
(-3325 5025);
FORCEPROP 3 LASTPIN (-3375 5025) SIG_NAME M_D_CPU0_SA_DQ<18>
J 0
(-3365 5035);
DISPLAY 0.659574 (-3365 5035);
PAINT MONO (-3365 5035);
DISPLAY INVISIBLE (-3365 5035);
FORCEPROP 1 LASTPIN (-3375 5025) BN 18
J 0
(-3387 5033);
DISPLAY 0.489362 (-3387 5033);
PAINT GREEN (-3387 5033);
FORCEPROP 2 LAST CDS_LIB mstr_standard
J 0
(-3325 5025);
DISPLAY 0.723404 (-3325 5025);
PAINT MONO (-3325 5025);
DISPLAY INVISIBLE (-3325 5025);
FORCEPROP 1 LAST BODY_TYPE PLUMBING
J 0
(-3325 5075);
DISPLAY 0.872340 (-3325 5075);
PAINT GREEN (-3325 5075);
DISPLAY INVISIBLE (-3325 5075);
FORCEPROP 1 LAST HDL_TAP TRUE
J 0
(-3000 4900);
DISPLAY 0.872340 (-3000 4900);
DISPLAY INVISIBLE (-3000 4900);
FORCEPROP 1 LAST PATH I179
J 0
(-3327 5025);
DISPLAY 0.872340 (-3327 5025);
PAINT GREEN (-3327 5025);
DISPLAY INVISIBLE (-3327 5025);
FORCEADD TAP..1
(-3325 5075);
FORCEPROP 3 LASTPIN (-3375 5075) SIG_NAME M_D_CPU0_SA_DQ<17>
J 0
(-3365 5085);
DISPLAY 0.659574 (-3365 5085);
PAINT MONO (-3365 5085);
DISPLAY INVISIBLE (-3365 5085);
FORCEPROP 1 LASTPIN (-3375 5075) BN 17
J 0
(-3387 5083);
DISPLAY 0.489362 (-3387 5083);
PAINT GREEN (-3387 5083);
FORCEPROP 2 LAST CDS_LIB mstr_standard
J 0
(-3325 5075);
DISPLAY 0.723404 (-3325 5075);
PAINT MONO (-3325 5075);
DISPLAY INVISIBLE (-3325 5075);
FORCEPROP 1 LAST BODY_TYPE PLUMBING
J 0
(-3325 5125);
DISPLAY 0.872340 (-3325 5125);
PAINT GREEN (-3325 5125);
DISPLAY INVISIBLE (-3325 5125);
FORCEPROP 1 LAST HDL_TAP TRUE
J 0
(-3000 4950);
DISPLAY 0.872340 (-3000 4950);
DISPLAY INVISIBLE (-3000 4950);
FORCEPROP 1 LAST PATH I180
J 0
(-3327 5075);
DISPLAY 0.872340 (-3327 5075);
PAINT GREEN (-3327 5075);
DISPLAY INVISIBLE (-3327 5075);
FORCEADD TAP..1
(-3325 4975);
FORCEPROP 3 LASTPIN (-3375 4975) SIG_NAME M_D_CPU0_SA_DQ<19>
J 0
(-3365 4985);
DISPLAY 0.659574 (-3365 4985);
PAINT MONO (-3365 4985);
DISPLAY INVISIBLE (-3365 4985);
FORCEPROP 1 LASTPIN (-3375 4975) BN 19
J 0
(-3387 4983);
DISPLAY 0.489362 (-3387 4983);
PAINT GREEN (-3387 4983);
FORCEPROP 2 LAST CDS_LIB mstr_standard
J 0
(-3325 4975);
DISPLAY 0.723404 (-3325 4975);
PAINT MONO (-3325 4975);
DISPLAY INVISIBLE (-3325 4975);
FORCEPROP 1 LAST BODY_TYPE PLUMBING
J 0
(-3325 5025);
DISPLAY 0.872340 (-3325 5025);
PAINT GREEN (-3325 5025);
DISPLAY INVISIBLE (-3325 5025);
FORCEPROP 1 LAST HDL_TAP TRUE
J 0
(-3000 4850);
DISPLAY 0.872340 (-3000 4850);
DISPLAY INVISIBLE (-3000 4850);
FORCEPROP 1 LAST PATH I181
J 0
(-3327 4975);
DISPLAY 0.872340 (-3327 4975);
PAINT GREEN (-3327 4975);
DISPLAY INVISIBLE (-3327 4975);
FORCEADD TAP..1
(-3325 4875);
FORCEPROP 3 LASTPIN (-3375 4875) SIG_NAME M_D_CPU0_SA_DQ<21>
J 0
(-3365 4885);
DISPLAY 0.659574 (-3365 4885);
PAINT MONO (-3365 4885);
DISPLAY INVISIBLE (-3365 4885);
FORCEPROP 1 LASTPIN (-3375 4875) BN 21
J 0
(-3387 4883);
DISPLAY 0.489362 (-3387 4883);
PAINT GREEN (-3387 4883);
FORCEPROP 2 LAST CDS_LIB mstr_standard
J 0
(-3325 4875);
DISPLAY 0.723404 (-3325 4875);
PAINT MONO (-3325 4875);
DISPLAY INVISIBLE (-3325 4875);
FORCEPROP 1 LAST BODY_TYPE PLUMBING
J 0
(-3325 4925);
DISPLAY 0.872340 (-3325 4925);
PAINT GREEN (-3325 4925);
DISPLAY INVISIBLE (-3325 4925);
FORCEPROP 1 LAST HDL_TAP TRUE
J 0
(-3000 4750);
DISPLAY 0.872340 (-3000 4750);
DISPLAY INVISIBLE (-3000 4750);
FORCEPROP 1 LAST PATH I182
J 0
(-3327 4875);
DISPLAY 0.872340 (-3327 4875);
PAINT GREEN (-3327 4875);
DISPLAY INVISIBLE (-3327 4875);
FORCEADD TAP..1
(-3325 4925);
FORCEPROP 3 LASTPIN (-3375 4925) SIG_NAME M_D_CPU0_SA_DQ<20>
J 0
(-3365 4935);
DISPLAY 0.659574 (-3365 4935);
PAINT MONO (-3365 4935);
DISPLAY INVISIBLE (-3365 4935);
FORCEPROP 1 LASTPIN (-3375 4925) BN 20
J 0
(-3387 4933);
DISPLAY 0.489362 (-3387 4933);
PAINT GREEN (-3387 4933);
FORCEPROP 2 LAST CDS_LIB mstr_standard
J 0
(-3325 4925);
DISPLAY 0.723404 (-3325 4925);
PAINT MONO (-3325 4925);
DISPLAY INVISIBLE (-3325 4925);
FORCEPROP 1 LAST BODY_TYPE PLUMBING
J 0
(-3325 4975);
DISPLAY 0.872340 (-3325 4975);
PAINT GREEN (-3325 4975);
DISPLAY INVISIBLE (-3325 4975);
FORCEPROP 1 LAST HDL_TAP TRUE
J 0
(-3000 4800);
DISPLAY 0.872340 (-3000 4800);
DISPLAY INVISIBLE (-3000 4800);
FORCEPROP 1 LAST PATH I183
J 0
(-3327 4925);
DISPLAY 0.872340 (-3327 4925);
PAINT GREEN (-3327 4925);
DISPLAY INVISIBLE (-3327 4925);
FORCEADD TAP..1
(-3325 4675);
FORCEPROP 3 LASTPIN (-3375 4675) SIG_NAME M_D_CPU0_SA_DQ<24>
J 0
(-3365 4685);
DISPLAY 0.659574 (-3365 4685);
PAINT MONO (-3365 4685);
DISPLAY INVISIBLE (-3365 4685);
FORCEPROP 1 LASTPIN (-3375 4675) BN 24
J 0
(-3387 4683);
DISPLAY 0.489362 (-3387 4683);
PAINT GREEN (-3387 4683);
FORCEPROP 2 LAST CDS_LIB mstr_standard
J 0
(-3325 4675);
DISPLAY 0.723404 (-3325 4675);
PAINT MONO (-3325 4675);
DISPLAY INVISIBLE (-3325 4675);
FORCEPROP 1 LAST BODY_TYPE PLUMBING
J 0
(-3325 4725);
DISPLAY 0.872340 (-3325 4725);
PAINT GREEN (-3325 4725);
DISPLAY INVISIBLE (-3325 4725);
FORCEPROP 1 LAST HDL_TAP TRUE
J 0
(-3000 4550);
DISPLAY 0.872340 (-3000 4550);
DISPLAY INVISIBLE (-3000 4550);
FORCEPROP 1 LAST PATH I184
J 0
(-3327 4675);
DISPLAY 0.872340 (-3327 4675);
PAINT GREEN (-3327 4675);
DISPLAY INVISIBLE (-3327 4675);
FORCEADD TAP..1
(-3325 4625);
FORCEPROP 3 LASTPIN (-3375 4625) SIG_NAME M_D_CPU0_SA_DQ<25>
J 0
(-3365 4635);
DISPLAY 0.659574 (-3365 4635);
PAINT MONO (-3365 4635);
DISPLAY INVISIBLE (-3365 4635);
FORCEPROP 1 LASTPIN (-3375 4625) BN 25
J 0
(-3387 4633);
DISPLAY 0.489362 (-3387 4633);
PAINT GREEN (-3387 4633);
FORCEPROP 2 LAST CDS_LIB mstr_standard
J 0
(-3325 4625);
DISPLAY 0.723404 (-3325 4625);
PAINT MONO (-3325 4625);
DISPLAY INVISIBLE (-3325 4625);
FORCEPROP 1 LAST BODY_TYPE PLUMBING
J 0
(-3325 4675);
DISPLAY 0.872340 (-3325 4675);
PAINT GREEN (-3325 4675);
DISPLAY INVISIBLE (-3325 4675);
FORCEPROP 1 LAST HDL_TAP TRUE
J 0
(-3000 4500);
DISPLAY 0.872340 (-3000 4500);
DISPLAY INVISIBLE (-3000 4500);
FORCEPROP 1 LAST PATH I185
J 0
(-3327 4625);
DISPLAY 0.872340 (-3327 4625);
PAINT GREEN (-3327 4625);
DISPLAY INVISIBLE (-3327 4625);
FORCEADD TAP..1
(-3325 4775);
FORCEPROP 3 LASTPIN (-3375 4775) SIG_NAME M_D_CPU0_SA_DQ<23>
J 0
(-3365 4785);
DISPLAY 0.659574 (-3365 4785);
PAINT MONO (-3365 4785);
DISPLAY INVISIBLE (-3365 4785);
FORCEPROP 1 LASTPIN (-3375 4775) BN 23
J 0
(-3387 4783);
DISPLAY 0.489362 (-3387 4783);
PAINT GREEN (-3387 4783);
FORCEPROP 2 LAST CDS_LIB mstr_standard
J 0
(-3325 4775);
DISPLAY 0.723404 (-3325 4775);
PAINT MONO (-3325 4775);
DISPLAY INVISIBLE (-3325 4775);
FORCEPROP 1 LAST BODY_TYPE PLUMBING
J 0
(-3325 4825);
DISPLAY 0.872340 (-3325 4825);
PAINT GREEN (-3325 4825);
DISPLAY INVISIBLE (-3325 4825);
FORCEPROP 1 LAST HDL_TAP TRUE
J 0
(-3000 4650);
DISPLAY 0.872340 (-3000 4650);
DISPLAY INVISIBLE (-3000 4650);
FORCEPROP 1 LAST PATH I186
J 0
(-3327 4775);
DISPLAY 0.872340 (-3327 4775);
PAINT GREEN (-3327 4775);
DISPLAY INVISIBLE (-3327 4775);
FORCEADD TAP..1
(-3325 4825);
FORCEPROP 3 LASTPIN (-3375 4825) SIG_NAME M_D_CPU0_SA_DQ<22>
J 0
(-3365 4835);
DISPLAY 0.659574 (-3365 4835);
PAINT MONO (-3365 4835);
DISPLAY INVISIBLE (-3365 4835);
FORCEPROP 1 LASTPIN (-3375 4825) BN 22
J 0
(-3387 4833);
DISPLAY 0.489362 (-3387 4833);
PAINT GREEN (-3387 4833);
FORCEPROP 2 LAST CDS_LIB mstr_standard
J 0
(-3325 4825);
DISPLAY 0.723404 (-3325 4825);
PAINT MONO (-3325 4825);
DISPLAY INVISIBLE (-3325 4825);
FORCEPROP 1 LAST BODY_TYPE PLUMBING
J 0
(-3325 4875);
DISPLAY 0.872340 (-3325 4875);
PAINT GREEN (-3325 4875);
DISPLAY INVISIBLE (-3325 4875);
FORCEPROP 1 LAST HDL_TAP TRUE
J 0
(-3000 4700);
DISPLAY 0.872340 (-3000 4700);
DISPLAY INVISIBLE (-3000 4700);
FORCEPROP 1 LAST PATH I187
J 0
(-3327 4825);
DISPLAY 0.872340 (-3327 4825);
PAINT GREEN (-3327 4825);
DISPLAY INVISIBLE (-3327 4825);
FORCEADD TAP..1
(-3325 4575);
FORCEPROP 3 LASTPIN (-3375 4575) SIG_NAME M_D_CPU0_SA_DQ<26>
J 0
(-3365 4585);
DISPLAY 0.659574 (-3365 4585);
PAINT MONO (-3365 4585);
DISPLAY INVISIBLE (-3365 4585);
FORCEPROP 1 LASTPIN (-3375 4575) BN 26
J 0
(-3387 4583);
DISPLAY 0.489362 (-3387 4583);
PAINT GREEN (-3387 4583);
FORCEPROP 2 LAST CDS_LIB mstr_standard
J 0
(-3325 4575);
DISPLAY 0.723404 (-3325 4575);
PAINT MONO (-3325 4575);
DISPLAY INVISIBLE (-3325 4575);
FORCEPROP 1 LAST BODY_TYPE PLUMBING
J 0
(-3325 4625);
DISPLAY 0.872340 (-3325 4625);
PAINT GREEN (-3325 4625);
DISPLAY INVISIBLE (-3325 4625);
FORCEPROP 1 LAST HDL_TAP TRUE
J 0
(-3000 4450);
DISPLAY 0.872340 (-3000 4450);
DISPLAY INVISIBLE (-3000 4450);
FORCEPROP 1 LAST PATH I188
J 0
(-3327 4575);
DISPLAY 0.872340 (-3327 4575);
PAINT GREEN (-3327 4575);
DISPLAY INVISIBLE (-3327 4575);
FORCEADD TAP..1
(-3325 4525);
FORCEPROP 3 LASTPIN (-3375 4525) SIG_NAME M_D_CPU0_SA_DQ<27>
J 0
(-3365 4535);
DISPLAY 0.659574 (-3365 4535);
PAINT MONO (-3365 4535);
DISPLAY INVISIBLE (-3365 4535);
FORCEPROP 1 LASTPIN (-3375 4525) BN 27
J 0
(-3387 4533);
DISPLAY 0.489362 (-3387 4533);
PAINT GREEN (-3387 4533);
FORCEPROP 2 LAST CDS_LIB mstr_standard
J 0
(-3325 4525);
DISPLAY 0.723404 (-3325 4525);
PAINT MONO (-3325 4525);
DISPLAY INVISIBLE (-3325 4525);
FORCEPROP 1 LAST BODY_TYPE PLUMBING
J 0
(-3325 4575);
DISPLAY 0.872340 (-3325 4575);
PAINT GREEN (-3325 4575);
DISPLAY INVISIBLE (-3325 4575);
FORCEPROP 1 LAST HDL_TAP TRUE
J 0
(-3000 4400);
DISPLAY 0.872340 (-3000 4400);
DISPLAY INVISIBLE (-3000 4400);
FORCEPROP 1 LAST PATH I189
J 0
(-3327 4525);
DISPLAY 0.872340 (-3327 4525);
PAINT GREEN (-3327 4525);
DISPLAY INVISIBLE (-3327 4525);
FORCEADD TAP..1
(-3325 4475);
FORCEPROP 3 LASTPIN (-3375 4475) SIG_NAME M_D_CPU0_SA_DQ<28>
J 0
(-3365 4485);
DISPLAY 0.659574 (-3365 4485);
PAINT MONO (-3365 4485);
DISPLAY INVISIBLE (-3365 4485);
FORCEPROP 1 LASTPIN (-3375 4475) BN 28
J 0
(-3387 4483);
DISPLAY 0.489362 (-3387 4483);
PAINT GREEN (-3387 4483);
FORCEPROP 2 LAST CDS_LIB mstr_standard
J 0
(-3325 4475);
DISPLAY 0.723404 (-3325 4475);
PAINT MONO (-3325 4475);
DISPLAY INVISIBLE (-3325 4475);
FORCEPROP 1 LAST BODY_TYPE PLUMBING
J 0
(-3325 4525);
DISPLAY 0.872340 (-3325 4525);
PAINT GREEN (-3325 4525);
DISPLAY INVISIBLE (-3325 4525);
FORCEPROP 1 LAST HDL_TAP TRUE
J 0
(-3000 4350);
DISPLAY 0.872340 (-3000 4350);
DISPLAY INVISIBLE (-3000 4350);
FORCEPROP 1 LAST PATH I190
J 0
(-3327 4475);
DISPLAY 0.872340 (-3327 4475);
PAINT GREEN (-3327 4475);
DISPLAY INVISIBLE (-3327 4475);
FORCEADD TAP..1
(-3325 4375);
FORCEPROP 3 LASTPIN (-3375 4375) SIG_NAME M_D_CPU0_SA_DQ<30>
J 0
(-3365 4385);
DISPLAY 0.659574 (-3365 4385);
PAINT MONO (-3365 4385);
DISPLAY INVISIBLE (-3365 4385);
FORCEPROP 1 LASTPIN (-3375 4375) BN 30
J 0
(-3387 4383);
DISPLAY 0.489362 (-3387 4383);
PAINT GREEN (-3387 4383);
FORCEPROP 2 LAST CDS_LIB mstr_standard
J 0
(-3325 4375);
DISPLAY 0.723404 (-3325 4375);
PAINT MONO (-3325 4375);
DISPLAY INVISIBLE (-3325 4375);
FORCEPROP 1 LAST BODY_TYPE PLUMBING
J 0
(-3325 4425);
DISPLAY 0.872340 (-3325 4425);
PAINT GREEN (-3325 4425);
DISPLAY INVISIBLE (-3325 4425);
FORCEPROP 1 LAST HDL_TAP TRUE
J 0
(-3000 4250);
DISPLAY 0.872340 (-3000 4250);
DISPLAY INVISIBLE (-3000 4250);
FORCEPROP 1 LAST PATH I191
J 0
(-3327 4375);
DISPLAY 0.872340 (-3327 4375);
PAINT GREEN (-3327 4375);
DISPLAY INVISIBLE (-3327 4375);
FORCEADD TAP..1
(-3325 4425);
FORCEPROP 3 LASTPIN (-3375 4425) SIG_NAME M_D_CPU0_SA_DQ<29>
J 0
(-3365 4435);
DISPLAY 0.659574 (-3365 4435);
PAINT MONO (-3365 4435);
DISPLAY INVISIBLE (-3365 4435);
FORCEPROP 1 LASTPIN (-3375 4425) BN 29
J 0
(-3387 4433);
DISPLAY 0.489362 (-3387 4433);
PAINT GREEN (-3387 4433);
FORCEPROP 2 LAST CDS_LIB mstr_standard
J 0
(-3325 4425);
DISPLAY 0.723404 (-3325 4425);
PAINT MONO (-3325 4425);
DISPLAY INVISIBLE (-3325 4425);
FORCEPROP 1 LAST BODY_TYPE PLUMBING
J 0
(-3325 4475);
DISPLAY 0.872340 (-3325 4475);
PAINT GREEN (-3325 4475);
DISPLAY INVISIBLE (-3325 4475);
FORCEPROP 1 LAST HDL_TAP TRUE
J 0
(-3000 4300);
DISPLAY 0.872340 (-3000 4300);
DISPLAY INVISIBLE (-3000 4300);
FORCEPROP 1 LAST PATH I192
J 0
(-3327 4425);
DISPLAY 0.872340 (-3327 4425);
PAINT GREEN (-3327 4425);
DISPLAY INVISIBLE (-3327 4425);
FORCEADD TAP..1
(-3325 4125);
FORCEPROP 3 LASTPIN (-3375 4125) SIG_NAME M_D_CPU0_SB_DQ<2>
J 0
(-3365 4135);
DISPLAY 0.659574 (-3365 4135);
PAINT MONO (-3365 4135);
DISPLAY INVISIBLE (-3365 4135);
FORCEPROP 1 LASTPIN (-3375 4125) BN 2
J 0
(-3387 4133);
DISPLAY 0.489362 (-3387 4133);
PAINT GREEN (-3387 4133);
FORCEPROP 2 LAST CDS_LIB mstr_standard
J 0
(-3325 4125);
DISPLAY 0.723404 (-3325 4125);
PAINT MONO (-3325 4125);
DISPLAY INVISIBLE (-3325 4125);
FORCEPROP 1 LAST BODY_TYPE PLUMBING
J 0
(-3325 4175);
DISPLAY 0.872340 (-3325 4175);
PAINT GREEN (-3325 4175);
DISPLAY INVISIBLE (-3325 4175);
FORCEPROP 1 LAST HDL_TAP TRUE
J 0
(-3000 4000);
DISPLAY 0.872340 (-3000 4000);
DISPLAY INVISIBLE (-3000 4000);
FORCEPROP 1 LAST PATH I193
J 0
(-3327 4125);
DISPLAY 0.872340 (-3327 4125);
PAINT GREEN (-3327 4125);
DISPLAY INVISIBLE (-3327 4125);
FORCEADD TAP..1
(-3325 4225);
FORCEPROP 3 LASTPIN (-3375 4225) SIG_NAME M_D_CPU0_SB_DQ<0>
J 0
(-3365 4235);
DISPLAY 0.659574 (-3365 4235);
PAINT MONO (-3365 4235);
DISPLAY INVISIBLE (-3365 4235);
FORCEPROP 1 LASTPIN (-3375 4225) BN 0
J 0
(-3387 4233);
DISPLAY 0.489362 (-3387 4233);
PAINT GREEN (-3387 4233);
FORCEPROP 2 LAST CDS_LIB mstr_standard
J 0
(-3325 4225);
DISPLAY 0.723404 (-3325 4225);
PAINT MONO (-3325 4225);
DISPLAY INVISIBLE (-3325 4225);
FORCEPROP 1 LAST BODY_TYPE PLUMBING
J 0
(-3325 4275);
DISPLAY 0.872340 (-3325 4275);
PAINT GREEN (-3325 4275);
DISPLAY INVISIBLE (-3325 4275);
FORCEPROP 1 LAST HDL_TAP TRUE
J 0
(-3000 4100);
DISPLAY 0.872340 (-3000 4100);
DISPLAY INVISIBLE (-3000 4100);
FORCEPROP 1 LAST PATH I194
J 0
(-3327 4225);
DISPLAY 0.872340 (-3327 4225);
PAINT GREEN (-3327 4225);
DISPLAY INVISIBLE (-3327 4225);
FORCEADD TAP..1
(-3325 4325);
FORCEPROP 3 LASTPIN (-3375 4325) SIG_NAME M_D_CPU0_SA_DQ<31>
J 0
(-3365 4335);
DISPLAY 0.659574 (-3365 4335);
PAINT MONO (-3365 4335);
DISPLAY INVISIBLE (-3365 4335);
FORCEPROP 1 LASTPIN (-3375 4325) BN 31
J 0
(-3387 4333);
DISPLAY 0.489362 (-3387 4333);
PAINT GREEN (-3387 4333);
FORCEPROP 2 LAST CDS_LIB mstr_standard
J 0
(-3325 4325);
DISPLAY 0.723404 (-3325 4325);
PAINT MONO (-3325 4325);
DISPLAY INVISIBLE (-3325 4325);
FORCEPROP 1 LAST BODY_TYPE PLUMBING
J 0
(-3325 4375);
DISPLAY 0.872340 (-3325 4375);
PAINT GREEN (-3325 4375);
DISPLAY INVISIBLE (-3325 4375);
FORCEPROP 1 LAST HDL_TAP TRUE
J 0
(-3000 4200);
DISPLAY 0.872340 (-3000 4200);
DISPLAY INVISIBLE (-3000 4200);
FORCEPROP 1 LAST PATH I195
J 0
(-3327 4325);
DISPLAY 0.872340 (-3327 4325);
PAINT GREEN (-3327 4325);
DISPLAY INVISIBLE (-3327 4325);
FORCEADD TAP..1
(-3325 4175);
FORCEPROP 3 LASTPIN (-3375 4175) SIG_NAME M_D_CPU0_SB_DQ<1>
J 0
(-3365 4185);
DISPLAY 0.659574 (-3365 4185);
PAINT MONO (-3365 4185);
DISPLAY INVISIBLE (-3365 4185);
FORCEPROP 1 LASTPIN (-3375 4175) BN 1
J 0
(-3387 4183);
DISPLAY 0.489362 (-3387 4183);
PAINT GREEN (-3387 4183);
FORCEPROP 2 LAST CDS_LIB mstr_standard
J 0
(-3325 4175);
DISPLAY 0.723404 (-3325 4175);
PAINT MONO (-3325 4175);
DISPLAY INVISIBLE (-3325 4175);
FORCEPROP 1 LAST BODY_TYPE PLUMBING
J 0
(-3325 4225);
DISPLAY 0.872340 (-3325 4225);
PAINT GREEN (-3325 4225);
DISPLAY INVISIBLE (-3325 4225);
FORCEPROP 1 LAST HDL_TAP TRUE
J 0
(-3000 4050);
DISPLAY 0.872340 (-3000 4050);
DISPLAY INVISIBLE (-3000 4050);
FORCEPROP 1 LAST PATH I196
J 0
(-3327 4175);
DISPLAY 0.872340 (-3327 4175);
PAINT GREEN (-3327 4175);
DISPLAY INVISIBLE (-3327 4175);
FORCEADD OFFPAGE..6
R 2
(-2725 2475);
FORCEPROP 2 LAST $XR0 89 
J 0
(-2511 2475);
DISPLAY 0.638298 (-2511 2475);
PAINT MONO (-2511 2475);
FORCEPROP 2 LAST CDS_LIB mstr_standard
J 2
(-2725 2475);
DISPLAY 0.723404 (-2725 2475);
PAINT MONO (-2725 2475);
DISPLAY INVISIBLE (-2725 2475);
FORCEPROP 1 LAST OFFPAGE TRUE
J 2
(-3050 2350);
DISPLAY 0.872340 (-3050 2350);
PAINT GREEN (-3050 2350);
DISPLAY INVISIBLE (-3050 2350);
FORCEPROP 1 LAST COMMENT_BODY TRUE
J 2
(-2825 2400);
DISPLAY 0.872340 (-2825 2400);
PAINT GREEN (-2825 2400);
DISPLAY INVISIBLE (-2825 2400);
FORCEPROP 2 LAST PATH I197
J 0
(-2500 2525);
DISPLAY 1.021277 (-2500 2525);
DISPLAY INVISIBLE (-2500 2525);
FORCEADD TAP..1
(-3325 3975);
FORCEPROP 3 LASTPIN (-3375 3975) SIG_NAME M_D_CPU0_SB_DQ<5>
J 0
(-3365 3985);
DISPLAY 0.659574 (-3365 3985);
PAINT MONO (-3365 3985);
DISPLAY INVISIBLE (-3365 3985);
FORCEPROP 1 LASTPIN (-3375 3975) BN 5
J 0
(-3387 3983);
DISPLAY 0.489362 (-3387 3983);
PAINT GREEN (-3387 3983);
FORCEPROP 2 LAST CDS_LIB mstr_standard
J 0
(-3325 3975);
DISPLAY 0.723404 (-3325 3975);
PAINT MONO (-3325 3975);
DISPLAY INVISIBLE (-3325 3975);
FORCEPROP 1 LAST BODY_TYPE PLUMBING
J 0
(-3325 4025);
DISPLAY 0.872340 (-3325 4025);
PAINT GREEN (-3325 4025);
DISPLAY INVISIBLE (-3325 4025);
FORCEPROP 1 LAST HDL_TAP TRUE
J 0
(-3000 3850);
DISPLAY 0.872340 (-3000 3850);
DISPLAY INVISIBLE (-3000 3850);
FORCEPROP 1 LAST PATH I198
J 0
(-3327 3975);
DISPLAY 0.872340 (-3327 3975);
PAINT GREEN (-3327 3975);
DISPLAY INVISIBLE (-3327 3975);
FORCEADD TAP..1
(-3325 4075);
FORCEPROP 3 LASTPIN (-3375 4075) SIG_NAME M_D_CPU0_SB_DQ<3>
J 0
(-3365 4085);
DISPLAY 0.659574 (-3365 4085);
PAINT MONO (-3365 4085);
DISPLAY INVISIBLE (-3365 4085);
FORCEPROP 1 LASTPIN (-3375 4075) BN 3
J 0
(-3387 4083);
DISPLAY 0.489362 (-3387 4083);
PAINT GREEN (-3387 4083);
FORCEPROP 2 LAST CDS_LIB mstr_standard
J 0
(-3325 4075);
DISPLAY 0.723404 (-3325 4075);
PAINT MONO (-3325 4075);
DISPLAY INVISIBLE (-3325 4075);
FORCEPROP 1 LAST BODY_TYPE PLUMBING
J 0
(-3325 4125);
DISPLAY 0.872340 (-3325 4125);
PAINT GREEN (-3325 4125);
DISPLAY INVISIBLE (-3325 4125);
FORCEPROP 1 LAST HDL_TAP TRUE
J 0
(-3000 3950);
DISPLAY 0.872340 (-3000 3950);
DISPLAY INVISIBLE (-3000 3950);
FORCEPROP 1 LAST PATH I199
J 0
(-3327 4075);
DISPLAY 0.872340 (-3327 4075);
PAINT GREEN (-3327 4075);
DISPLAY INVISIBLE (-3327 4075);
FORCEADD TAP..1
(-3325 4025);
FORCEPROP 3 LASTPIN (-3375 4025) SIG_NAME M_D_CPU0_SB_DQ<4>
J 0
(-3365 4035);
DISPLAY 0.659574 (-3365 4035);
PAINT MONO (-3365 4035);
DISPLAY INVISIBLE (-3365 4035);
FORCEPROP 1 LASTPIN (-3375 4025) BN 4
J 0
(-3387 4033);
DISPLAY 0.489362 (-3387 4033);
PAINT GREEN (-3387 4033);
FORCEPROP 2 LAST CDS_LIB mstr_standard
J 0
(-3325 4025);
DISPLAY 0.723404 (-3325 4025);
PAINT MONO (-3325 4025);
DISPLAY INVISIBLE (-3325 4025);
FORCEPROP 1 LAST BODY_TYPE PLUMBING
J 0
(-3325 4075);
DISPLAY 0.872340 (-3325 4075);
PAINT GREEN (-3325 4075);
DISPLAY INVISIBLE (-3325 4075);
FORCEPROP 1 LAST HDL_TAP TRUE
J 0
(-3000 3900);
DISPLAY 0.872340 (-3000 3900);
DISPLAY INVISIBLE (-3000 3900);
FORCEPROP 1 LAST PATH I200
J 0
(-3327 4025);
DISPLAY 0.872340 (-3327 4025);
PAINT GREEN (-3327 4025);
DISPLAY INVISIBLE (-3327 4025);
FORCEADD TAP..1
(-3325 3925);
FORCEPROP 3 LASTPIN (-3375 3925) SIG_NAME M_D_CPU0_SB_DQ<6>
J 0
(-3365 3935);
DISPLAY 0.659574 (-3365 3935);
PAINT MONO (-3365 3935);
DISPLAY INVISIBLE (-3365 3935);
FORCEPROP 1 LASTPIN (-3375 3925) BN 6
J 0
(-3387 3933);
DISPLAY 0.489362 (-3387 3933);
PAINT GREEN (-3387 3933);
FORCEPROP 2 LAST CDS_LIB mstr_standard
J 0
(-3325 3925);
DISPLAY 0.723404 (-3325 3925);
PAINT MONO (-3325 3925);
DISPLAY INVISIBLE (-3325 3925);
FORCEPROP 1 LAST BODY_TYPE PLUMBING
J 0
(-3325 3975);
DISPLAY 0.872340 (-3325 3975);
PAINT GREEN (-3325 3975);
DISPLAY INVISIBLE (-3325 3975);
FORCEPROP 1 LAST HDL_TAP TRUE
J 0
(-3000 3800);
DISPLAY 0.872340 (-3000 3800);
DISPLAY INVISIBLE (-3000 3800);
FORCEPROP 1 LAST PATH I201
J 0
(-3327 3925);
DISPLAY 0.872340 (-3327 3925);
PAINT GREEN (-3327 3925);
DISPLAY INVISIBLE (-3327 3925);
FORCEADD TAP..1
(-3325 3875);
FORCEPROP 3 LASTPIN (-3375 3875) SIG_NAME M_D_CPU0_SB_DQ<7>
J 0
(-3365 3885);
DISPLAY 0.659574 (-3365 3885);
PAINT MONO (-3365 3885);
DISPLAY INVISIBLE (-3365 3885);
FORCEPROP 1 LASTPIN (-3375 3875) BN 7
J 0
(-3387 3883);
DISPLAY 0.489362 (-3387 3883);
PAINT GREEN (-3387 3883);
FORCEPROP 2 LAST CDS_LIB mstr_standard
J 0
(-3325 3875);
DISPLAY 0.723404 (-3325 3875);
PAINT MONO (-3325 3875);
DISPLAY INVISIBLE (-3325 3875);
FORCEPROP 1 LAST BODY_TYPE PLUMBING
J 0
(-3325 3925);
DISPLAY 0.872340 (-3325 3925);
PAINT GREEN (-3325 3925);
DISPLAY INVISIBLE (-3325 3925);
FORCEPROP 1 LAST HDL_TAP TRUE
J 0
(-3000 3750);
DISPLAY 0.872340 (-3000 3750);
DISPLAY INVISIBLE (-3000 3750);
FORCEPROP 1 LAST PATH I202
J 0
(-3327 3875);
DISPLAY 0.872340 (-3327 3875);
PAINT GREEN (-3327 3875);
DISPLAY INVISIBLE (-3327 3875);
FORCEADD TAP..1
(-3325 3775);
FORCEPROP 3 LASTPIN (-3375 3775) SIG_NAME M_D_CPU0_SB_DQ<8>
J 0
(-3365 3785);
DISPLAY 0.659574 (-3365 3785);
PAINT MONO (-3365 3785);
DISPLAY INVISIBLE (-3365 3785);
FORCEPROP 1 LASTPIN (-3375 3775) BN 8
J 0
(-3387 3783);
DISPLAY 0.489362 (-3387 3783);
PAINT GREEN (-3387 3783);
FORCEPROP 2 LAST CDS_LIB mstr_standard
J 0
(-3325 3775);
DISPLAY 0.723404 (-3325 3775);
PAINT MONO (-3325 3775);
DISPLAY INVISIBLE (-3325 3775);
FORCEPROP 1 LAST BODY_TYPE PLUMBING
J 0
(-3325 3825);
DISPLAY 0.872340 (-3325 3825);
PAINT GREEN (-3325 3825);
DISPLAY INVISIBLE (-3325 3825);
FORCEPROP 1 LAST HDL_TAP TRUE
J 0
(-3000 3650);
DISPLAY 0.872340 (-3000 3650);
DISPLAY INVISIBLE (-3000 3650);
FORCEPROP 1 LAST PATH I203
J 0
(-3327 3775);
DISPLAY 0.872340 (-3327 3775);
PAINT GREEN (-3327 3775);
DISPLAY INVISIBLE (-3327 3775);
FORCEADD TAP..1
(-3325 3725);
FORCEPROP 3 LASTPIN (-3375 3725) SIG_NAME M_D_CPU0_SB_DQ<9>
J 0
(-3365 3735);
DISPLAY 0.659574 (-3365 3735);
PAINT MONO (-3365 3735);
DISPLAY INVISIBLE (-3365 3735);
FORCEPROP 1 LASTPIN (-3375 3725) BN 9
J 0
(-3387 3733);
DISPLAY 0.489362 (-3387 3733);
PAINT GREEN (-3387 3733);
FORCEPROP 2 LAST CDS_LIB mstr_standard
J 0
(-3325 3725);
DISPLAY 0.723404 (-3325 3725);
PAINT MONO (-3325 3725);
DISPLAY INVISIBLE (-3325 3725);
FORCEPROP 1 LAST BODY_TYPE PLUMBING
J 0
(-3325 3775);
DISPLAY 0.872340 (-3325 3775);
PAINT GREEN (-3325 3775);
DISPLAY INVISIBLE (-3325 3775);
FORCEPROP 1 LAST HDL_TAP TRUE
J 0
(-3000 3600);
DISPLAY 0.872340 (-3000 3600);
DISPLAY INVISIBLE (-3000 3600);
FORCEPROP 1 LAST PATH I204
J 0
(-3327 3725);
DISPLAY 0.872340 (-3327 3725);
PAINT GREEN (-3327 3725);
DISPLAY INVISIBLE (-3327 3725);
FORCEADD TAP..1
(-3325 3675);
FORCEPROP 3 LASTPIN (-3375 3675) SIG_NAME M_D_CPU0_SB_DQ<10>
J 0
(-3365 3685);
DISPLAY 0.659574 (-3365 3685);
PAINT MONO (-3365 3685);
DISPLAY INVISIBLE (-3365 3685);
FORCEPROP 1 LASTPIN (-3375 3675) BN 10
J 0
(-3387 3683);
DISPLAY 0.489362 (-3387 3683);
PAINT GREEN (-3387 3683);
FORCEPROP 2 LAST CDS_LIB mstr_standard
J 0
(-3325 3675);
DISPLAY 0.723404 (-3325 3675);
PAINT MONO (-3325 3675);
DISPLAY INVISIBLE (-3325 3675);
FORCEPROP 1 LAST BODY_TYPE PLUMBING
J 0
(-3325 3725);
DISPLAY 0.872340 (-3325 3725);
PAINT GREEN (-3325 3725);
DISPLAY INVISIBLE (-3325 3725);
FORCEPROP 1 LAST HDL_TAP TRUE
J 0
(-3000 3550);
DISPLAY 0.872340 (-3000 3550);
DISPLAY INVISIBLE (-3000 3550);
FORCEPROP 1 LAST PATH I205
J 0
(-3327 3675);
DISPLAY 0.872340 (-3327 3675);
PAINT GREEN (-3327 3675);
DISPLAY INVISIBLE (-3327 3675);
FORCEADD TAP..1
(-3325 3625);
FORCEPROP 3 LASTPIN (-3375 3625) SIG_NAME M_D_CPU0_SB_DQ<11>
J 0
(-3365 3635);
DISPLAY 0.659574 (-3365 3635);
PAINT MONO (-3365 3635);
DISPLAY INVISIBLE (-3365 3635);
FORCEPROP 1 LASTPIN (-3375 3625) BN 11
J 0
(-3387 3633);
DISPLAY 0.489362 (-3387 3633);
PAINT GREEN (-3387 3633);
FORCEPROP 2 LAST CDS_LIB mstr_standard
J 0
(-3325 3625);
DISPLAY 0.723404 (-3325 3625);
PAINT MONO (-3325 3625);
DISPLAY INVISIBLE (-3325 3625);
FORCEPROP 1 LAST BODY_TYPE PLUMBING
J 0
(-3325 3675);
DISPLAY 0.872340 (-3325 3675);
PAINT GREEN (-3325 3675);
DISPLAY INVISIBLE (-3325 3675);
FORCEPROP 1 LAST HDL_TAP TRUE
J 0
(-3000 3500);
DISPLAY 0.872340 (-3000 3500);
DISPLAY INVISIBLE (-3000 3500);
FORCEPROP 1 LAST PATH I206
J 0
(-3327 3625);
DISPLAY 0.872340 (-3327 3625);
PAINT GREEN (-3327 3625);
DISPLAY INVISIBLE (-3327 3625);
FORCEADD TAP..1
(-3325 3475);
FORCEPROP 3 LASTPIN (-3375 3475) SIG_NAME M_D_CPU0_SB_DQ<14>
J 0
(-3365 3485);
DISPLAY 0.659574 (-3365 3485);
PAINT MONO (-3365 3485);
DISPLAY INVISIBLE (-3365 3485);
FORCEPROP 1 LASTPIN (-3375 3475) BN 14
J 0
(-3387 3483);
DISPLAY 0.489362 (-3387 3483);
PAINT GREEN (-3387 3483);
FORCEPROP 2 LAST CDS_LIB mstr_standard
J 0
(-3325 3475);
DISPLAY 0.723404 (-3325 3475);
PAINT MONO (-3325 3475);
DISPLAY INVISIBLE (-3325 3475);
FORCEPROP 1 LAST BODY_TYPE PLUMBING
J 0
(-3325 3525);
DISPLAY 0.872340 (-3325 3525);
PAINT GREEN (-3325 3525);
DISPLAY INVISIBLE (-3325 3525);
FORCEPROP 1 LAST HDL_TAP TRUE
J 0
(-3000 3350);
DISPLAY 0.872340 (-3000 3350);
DISPLAY INVISIBLE (-3000 3350);
FORCEPROP 1 LAST PATH I207
J 0
(-3327 3475);
DISPLAY 0.872340 (-3327 3475);
PAINT GREEN (-3327 3475);
DISPLAY INVISIBLE (-3327 3475);
FORCEADD TAP..1
(-3325 3575);
FORCEPROP 3 LASTPIN (-3375 3575) SIG_NAME M_D_CPU0_SB_DQ<12>
J 0
(-3365 3585);
DISPLAY 0.659574 (-3365 3585);
PAINT MONO (-3365 3585);
DISPLAY INVISIBLE (-3365 3585);
FORCEPROP 1 LASTPIN (-3375 3575) BN 12
J 0
(-3387 3583);
DISPLAY 0.489362 (-3387 3583);
PAINT GREEN (-3387 3583);
FORCEPROP 2 LAST CDS_LIB mstr_standard
J 0
(-3325 3575);
DISPLAY 0.723404 (-3325 3575);
PAINT MONO (-3325 3575);
DISPLAY INVISIBLE (-3325 3575);
FORCEPROP 1 LAST BODY_TYPE PLUMBING
J 0
(-3325 3625);
DISPLAY 0.872340 (-3325 3625);
PAINT GREEN (-3325 3625);
DISPLAY INVISIBLE (-3325 3625);
FORCEPROP 1 LAST HDL_TAP TRUE
J 0
(-3000 3450);
DISPLAY 0.872340 (-3000 3450);
DISPLAY INVISIBLE (-3000 3450);
FORCEPROP 1 LAST PATH I208
J 0
(-3327 3575);
DISPLAY 0.872340 (-3327 3575);
PAINT GREEN (-3327 3575);
DISPLAY INVISIBLE (-3327 3575);
FORCEADD TAP..1
(-3325 3525);
FORCEPROP 3 LASTPIN (-3375 3525) SIG_NAME M_D_CPU0_SB_DQ<13>
J 0
(-3365 3535);
DISPLAY 0.659574 (-3365 3535);
PAINT MONO (-3365 3535);
DISPLAY INVISIBLE (-3365 3535);
FORCEPROP 1 LASTPIN (-3375 3525) BN 13
J 0
(-3387 3533);
DISPLAY 0.489362 (-3387 3533);
PAINT GREEN (-3387 3533);
FORCEPROP 2 LAST CDS_LIB mstr_standard
J 0
(-3325 3525);
DISPLAY 0.723404 (-3325 3525);
PAINT MONO (-3325 3525);
DISPLAY INVISIBLE (-3325 3525);
FORCEPROP 1 LAST BODY_TYPE PLUMBING
J 0
(-3325 3575);
DISPLAY 0.872340 (-3325 3575);
PAINT GREEN (-3325 3575);
DISPLAY INVISIBLE (-3325 3575);
FORCEPROP 1 LAST HDL_TAP TRUE
J 0
(-3000 3400);
DISPLAY 0.872340 (-3000 3400);
DISPLAY INVISIBLE (-3000 3400);
FORCEPROP 1 LAST PATH I209
J 0
(-3327 3525);
DISPLAY 0.872340 (-3327 3525);
PAINT GREEN (-3327 3525);
DISPLAY INVISIBLE (-3327 3525);
FORCEADD TAP..1
(-3325 3425);
FORCEPROP 3 LASTPIN (-3375 3425) SIG_NAME M_D_CPU0_SB_DQ<15>
J 0
(-3365 3435);
DISPLAY 0.659574 (-3365 3435);
PAINT MONO (-3365 3435);
DISPLAY INVISIBLE (-3365 3435);
FORCEPROP 1 LASTPIN (-3375 3425) BN 15
J 0
(-3387 3433);
DISPLAY 0.489362 (-3387 3433);
PAINT GREEN (-3387 3433);
FORCEPROP 2 LAST CDS_LIB mstr_standard
J 0
(-3325 3425);
DISPLAY 0.723404 (-3325 3425);
PAINT MONO (-3325 3425);
DISPLAY INVISIBLE (-3325 3425);
FORCEPROP 1 LAST BODY_TYPE PLUMBING
J 0
(-3325 3475);
DISPLAY 0.872340 (-3325 3475);
PAINT GREEN (-3325 3475);
DISPLAY INVISIBLE (-3325 3475);
FORCEPROP 1 LAST HDL_TAP TRUE
J 0
(-3000 3300);
DISPLAY 0.872340 (-3000 3300);
DISPLAY INVISIBLE (-3000 3300);
FORCEPROP 1 LAST PATH I210
J 0
(-3327 3425);
DISPLAY 0.872340 (-3327 3425);
PAINT GREEN (-3327 3425);
DISPLAY INVISIBLE (-3327 3425);
FORCEADD TAP..1
(-3325 3225);
FORCEPROP 3 LASTPIN (-3375 3225) SIG_NAME M_D_CPU0_SB_DQ<18>
J 0
(-3365 3235);
DISPLAY 0.659574 (-3365 3235);
PAINT MONO (-3365 3235);
DISPLAY INVISIBLE (-3365 3235);
FORCEPROP 1 LASTPIN (-3375 3225) BN 18
J 0
(-3387 3233);
DISPLAY 0.489362 (-3387 3233);
PAINT GREEN (-3387 3233);
FORCEPROP 2 LAST CDS_LIB mstr_standard
J 0
(-3325 3225);
DISPLAY 0.723404 (-3325 3225);
PAINT MONO (-3325 3225);
DISPLAY INVISIBLE (-3325 3225);
FORCEPROP 1 LAST BODY_TYPE PLUMBING
J 0
(-3325 3275);
DISPLAY 0.872340 (-3325 3275);
PAINT GREEN (-3325 3275);
DISPLAY INVISIBLE (-3325 3275);
FORCEPROP 1 LAST HDL_TAP TRUE
J 0
(-3000 3100);
DISPLAY 0.872340 (-3000 3100);
DISPLAY INVISIBLE (-3000 3100);
FORCEPROP 1 LAST PATH I211
J 0
(-3327 3225);
DISPLAY 0.872340 (-3327 3225);
PAINT GREEN (-3327 3225);
DISPLAY INVISIBLE (-3327 3225);
FORCEADD TAP..1
(-3325 3275);
FORCEPROP 3 LASTPIN (-3375 3275) SIG_NAME M_D_CPU0_SB_DQ<17>
J 0
(-3365 3285);
DISPLAY 0.659574 (-3365 3285);
PAINT MONO (-3365 3285);
DISPLAY INVISIBLE (-3365 3285);
FORCEPROP 1 LASTPIN (-3375 3275) BN 17
J 0
(-3387 3283);
DISPLAY 0.489362 (-3387 3283);
PAINT GREEN (-3387 3283);
FORCEPROP 2 LAST CDS_LIB mstr_standard
J 0
(-3325 3275);
DISPLAY 0.723404 (-3325 3275);
PAINT MONO (-3325 3275);
DISPLAY INVISIBLE (-3325 3275);
FORCEPROP 1 LAST BODY_TYPE PLUMBING
J 0
(-3325 3325);
DISPLAY 0.872340 (-3325 3325);
PAINT GREEN (-3325 3325);
DISPLAY INVISIBLE (-3325 3325);
FORCEPROP 1 LAST HDL_TAP TRUE
J 0
(-3000 3150);
DISPLAY 0.872340 (-3000 3150);
DISPLAY INVISIBLE (-3000 3150);
FORCEPROP 1 LAST PATH I212
J 0
(-3327 3275);
DISPLAY 0.872340 (-3327 3275);
PAINT GREEN (-3327 3275);
DISPLAY INVISIBLE (-3327 3275);
FORCEADD TAP..1
(-3325 3325);
FORCEPROP 3 LASTPIN (-3375 3325) SIG_NAME M_D_CPU0_SB_DQ<16>
J 0
(-3365 3335);
DISPLAY 0.659574 (-3365 3335);
PAINT MONO (-3365 3335);
DISPLAY INVISIBLE (-3365 3335);
FORCEPROP 1 LASTPIN (-3375 3325) BN 16
J 0
(-3387 3333);
DISPLAY 0.489362 (-3387 3333);
PAINT GREEN (-3387 3333);
FORCEPROP 2 LAST CDS_LIB mstr_standard
J 0
(-3325 3325);
DISPLAY 0.723404 (-3325 3325);
PAINT MONO (-3325 3325);
DISPLAY INVISIBLE (-3325 3325);
FORCEPROP 1 LAST BODY_TYPE PLUMBING
J 0
(-3325 3375);
DISPLAY 0.872340 (-3325 3375);
PAINT GREEN (-3325 3375);
DISPLAY INVISIBLE (-3325 3375);
FORCEPROP 1 LAST HDL_TAP TRUE
J 0
(-3000 3200);
DISPLAY 0.872340 (-3000 3200);
DISPLAY INVISIBLE (-3000 3200);
FORCEPROP 1 LAST PATH I213
J 0
(-3327 3325);
DISPLAY 0.872340 (-3327 3325);
PAINT GREEN (-3327 3325);
DISPLAY INVISIBLE (-3327 3325);
FORCEADD TAP..1
(-3325 3075);
FORCEPROP 3 LASTPIN (-3375 3075) SIG_NAME M_D_CPU0_SB_DQ<21>
J 0
(-3365 3085);
DISPLAY 0.659574 (-3365 3085);
PAINT MONO (-3365 3085);
DISPLAY INVISIBLE (-3365 3085);
FORCEPROP 1 LASTPIN (-3375 3075) BN 21
J 0
(-3387 3083);
DISPLAY 0.489362 (-3387 3083);
PAINT GREEN (-3387 3083);
FORCEPROP 2 LAST CDS_LIB mstr_standard
J 0
(-3325 3075);
DISPLAY 0.723404 (-3325 3075);
PAINT MONO (-3325 3075);
DISPLAY INVISIBLE (-3325 3075);
FORCEPROP 1 LAST BODY_TYPE PLUMBING
J 0
(-3325 3125);
DISPLAY 0.872340 (-3325 3125);
PAINT GREEN (-3325 3125);
DISPLAY INVISIBLE (-3325 3125);
FORCEPROP 1 LAST HDL_TAP TRUE
J 0
(-3000 2950);
DISPLAY 0.872340 (-3000 2950);
DISPLAY INVISIBLE (-3000 2950);
FORCEPROP 1 LAST PATH I214
J 0
(-3327 3075);
DISPLAY 0.872340 (-3327 3075);
PAINT GREEN (-3327 3075);
DISPLAY INVISIBLE (-3327 3075);
FORCEADD TAP..1
(-3325 3175);
FORCEPROP 3 LASTPIN (-3375 3175) SIG_NAME M_D_CPU0_SB_DQ<19>
J 0
(-3365 3185);
DISPLAY 0.659574 (-3365 3185);
PAINT MONO (-3365 3185);
DISPLAY INVISIBLE (-3365 3185);
FORCEPROP 1 LASTPIN (-3375 3175) BN 19
J 0
(-3387 3183);
DISPLAY 0.489362 (-3387 3183);
PAINT GREEN (-3387 3183);
FORCEPROP 2 LAST CDS_LIB mstr_standard
J 0
(-3325 3175);
DISPLAY 0.723404 (-3325 3175);
PAINT MONO (-3325 3175);
DISPLAY INVISIBLE (-3325 3175);
FORCEPROP 1 LAST BODY_TYPE PLUMBING
J 0
(-3325 3225);
DISPLAY 0.872340 (-3325 3225);
PAINT GREEN (-3325 3225);
DISPLAY INVISIBLE (-3325 3225);
FORCEPROP 1 LAST HDL_TAP TRUE
J 0
(-3000 3050);
DISPLAY 0.872340 (-3000 3050);
DISPLAY INVISIBLE (-3000 3050);
FORCEPROP 1 LAST PATH I215
J 0
(-3327 3175);
DISPLAY 0.872340 (-3327 3175);
PAINT GREEN (-3327 3175);
DISPLAY INVISIBLE (-3327 3175);
FORCEADD TAP..1
(-3325 3125);
FORCEPROP 3 LASTPIN (-3375 3125) SIG_NAME M_D_CPU0_SB_DQ<20>
J 0
(-3365 3135);
DISPLAY 0.659574 (-3365 3135);
PAINT MONO (-3365 3135);
DISPLAY INVISIBLE (-3365 3135);
FORCEPROP 1 LASTPIN (-3375 3125) BN 20
J 0
(-3387 3133);
DISPLAY 0.489362 (-3387 3133);
PAINT GREEN (-3387 3133);
FORCEPROP 2 LAST CDS_LIB mstr_standard
J 0
(-3325 3125);
DISPLAY 0.723404 (-3325 3125);
PAINT MONO (-3325 3125);
DISPLAY INVISIBLE (-3325 3125);
FORCEPROP 1 LAST BODY_TYPE PLUMBING
J 0
(-3325 3175);
DISPLAY 0.872340 (-3325 3175);
PAINT GREEN (-3325 3175);
DISPLAY INVISIBLE (-3325 3175);
FORCEPROP 1 LAST HDL_TAP TRUE
J 0
(-3000 3000);
DISPLAY 0.872340 (-3000 3000);
DISPLAY INVISIBLE (-3000 3000);
FORCEPROP 1 LAST PATH I216
J 0
(-3327 3125);
DISPLAY 0.872340 (-3327 3125);
PAINT GREEN (-3327 3125);
DISPLAY INVISIBLE (-3327 3125);
FORCEADD TAP..1
(-3325 2975);
FORCEPROP 3 LASTPIN (-3375 2975) SIG_NAME M_D_CPU0_SB_DQ<23>
J 0
(-3365 2985);
DISPLAY 0.659574 (-3365 2985);
PAINT MONO (-3365 2985);
DISPLAY INVISIBLE (-3365 2985);
FORCEPROP 1 LASTPIN (-3375 2975) BN 23
J 0
(-3387 2983);
DISPLAY 0.489362 (-3387 2983);
PAINT GREEN (-3387 2983);
FORCEPROP 2 LAST CDS_LIB mstr_standard
J 0
(-3325 2975);
DISPLAY 0.723404 (-3325 2975);
PAINT MONO (-3325 2975);
DISPLAY INVISIBLE (-3325 2975);
FORCEPROP 1 LAST BODY_TYPE PLUMBING
J 0
(-3325 3025);
DISPLAY 0.872340 (-3325 3025);
PAINT GREEN (-3325 3025);
DISPLAY INVISIBLE (-3325 3025);
FORCEPROP 1 LAST HDL_TAP TRUE
J 0
(-3000 2850);
DISPLAY 0.872340 (-3000 2850);
DISPLAY INVISIBLE (-3000 2850);
FORCEPROP 1 LAST PATH I217
J 0
(-3327 2975);
DISPLAY 0.872340 (-3327 2975);
PAINT GREEN (-3327 2975);
DISPLAY INVISIBLE (-3327 2975);
FORCEADD TAP..1
(-3325 2875);
FORCEPROP 3 LASTPIN (-3375 2875) SIG_NAME M_D_CPU0_SB_DQ<24>
J 0
(-3365 2885);
DISPLAY 0.659574 (-3365 2885);
PAINT MONO (-3365 2885);
DISPLAY INVISIBLE (-3365 2885);
FORCEPROP 1 LASTPIN (-3375 2875) BN 24
J 0
(-3387 2883);
DISPLAY 0.489362 (-3387 2883);
PAINT GREEN (-3387 2883);
FORCEPROP 2 LAST CDS_LIB mstr_standard
J 0
(-3325 2875);
DISPLAY 0.723404 (-3325 2875);
PAINT MONO (-3325 2875);
DISPLAY INVISIBLE (-3325 2875);
FORCEPROP 1 LAST BODY_TYPE PLUMBING
J 0
(-3325 2925);
DISPLAY 0.872340 (-3325 2925);
PAINT GREEN (-3325 2925);
DISPLAY INVISIBLE (-3325 2925);
FORCEPROP 1 LAST HDL_TAP TRUE
J 0
(-3000 2750);
DISPLAY 0.872340 (-3000 2750);
DISPLAY INVISIBLE (-3000 2750);
FORCEPROP 1 LAST PATH I218
J 0
(-3327 2875);
DISPLAY 0.872340 (-3327 2875);
PAINT GREEN (-3327 2875);
DISPLAY INVISIBLE (-3327 2875);
FORCEADD TAP..1
(-3325 3025);
FORCEPROP 3 LASTPIN (-3375 3025) SIG_NAME M_D_CPU0_SB_DQ<22>
J 0
(-3365 3035);
DISPLAY 0.659574 (-3365 3035);
PAINT MONO (-3365 3035);
DISPLAY INVISIBLE (-3365 3035);
FORCEPROP 1 LASTPIN (-3375 3025) BN 22
J 0
(-3387 3033);
DISPLAY 0.489362 (-3387 3033);
PAINT GREEN (-3387 3033);
FORCEPROP 2 LAST CDS_LIB mstr_standard
J 0
(-3325 3025);
DISPLAY 0.723404 (-3325 3025);
PAINT MONO (-3325 3025);
DISPLAY INVISIBLE (-3325 3025);
FORCEPROP 1 LAST BODY_TYPE PLUMBING
J 0
(-3325 3075);
DISPLAY 0.872340 (-3325 3075);
PAINT GREEN (-3325 3075);
DISPLAY INVISIBLE (-3325 3075);
FORCEPROP 1 LAST HDL_TAP TRUE
J 0
(-3000 2900);
DISPLAY 0.872340 (-3000 2900);
DISPLAY INVISIBLE (-3000 2900);
FORCEPROP 1 LAST PATH I219
J 0
(-3327 3025);
DISPLAY 0.872340 (-3327 3025);
PAINT GREEN (-3327 3025);
DISPLAY INVISIBLE (-3327 3025);
FORCEADD TAP..1
(-3325 2825);
FORCEPROP 3 LASTPIN (-3375 2825) SIG_NAME M_D_CPU0_SB_DQ<25>
J 0
(-3365 2835);
DISPLAY 0.659574 (-3365 2835);
PAINT MONO (-3365 2835);
DISPLAY INVISIBLE (-3365 2835);
FORCEPROP 1 LASTPIN (-3375 2825) BN 25
J 0
(-3387 2833);
DISPLAY 0.489362 (-3387 2833);
PAINT GREEN (-3387 2833);
FORCEPROP 2 LAST CDS_LIB mstr_standard
J 0
(-3325 2825);
DISPLAY 0.723404 (-3325 2825);
PAINT MONO (-3325 2825);
DISPLAY INVISIBLE (-3325 2825);
FORCEPROP 1 LAST BODY_TYPE PLUMBING
J 0
(-3325 2875);
DISPLAY 0.872340 (-3325 2875);
PAINT GREEN (-3325 2875);
DISPLAY INVISIBLE (-3325 2875);
FORCEPROP 1 LAST HDL_TAP TRUE
J 0
(-3000 2700);
DISPLAY 0.872340 (-3000 2700);
DISPLAY INVISIBLE (-3000 2700);
FORCEPROP 1 LAST PATH I220
J 0
(-3327 2825);
DISPLAY 0.872340 (-3327 2825);
PAINT GREEN (-3327 2825);
DISPLAY INVISIBLE (-3327 2825);
FORCEADD TAP..1
(-3325 2775);
FORCEPROP 3 LASTPIN (-3375 2775) SIG_NAME M_D_CPU0_SB_DQ<26>
J 0
(-3365 2785);
DISPLAY 0.659574 (-3365 2785);
PAINT MONO (-3365 2785);
DISPLAY INVISIBLE (-3365 2785);
FORCEPROP 1 LASTPIN (-3375 2775) BN 26
J 0
(-3387 2783);
DISPLAY 0.489362 (-3387 2783);
PAINT GREEN (-3387 2783);
FORCEPROP 2 LAST CDS_LIB mstr_standard
J 0
(-3325 2775);
DISPLAY 0.723404 (-3325 2775);
PAINT MONO (-3325 2775);
DISPLAY INVISIBLE (-3325 2775);
FORCEPROP 1 LAST BODY_TYPE PLUMBING
J 0
(-3325 2825);
DISPLAY 0.872340 (-3325 2825);
PAINT GREEN (-3325 2825);
DISPLAY INVISIBLE (-3325 2825);
FORCEPROP 1 LAST HDL_TAP TRUE
J 0
(-3000 2650);
DISPLAY 0.872340 (-3000 2650);
DISPLAY INVISIBLE (-3000 2650);
FORCEPROP 1 LAST PATH I221
J 0
(-3327 2775);
DISPLAY 0.872340 (-3327 2775);
PAINT GREEN (-3327 2775);
DISPLAY INVISIBLE (-3327 2775);
FORCEADD TAP..1
(-3325 2725);
FORCEPROP 3 LASTPIN (-3375 2725) SIG_NAME M_D_CPU0_SB_DQ<27>
J 0
(-3365 2735);
DISPLAY 0.659574 (-3365 2735);
PAINT MONO (-3365 2735);
DISPLAY INVISIBLE (-3365 2735);
FORCEPROP 1 LASTPIN (-3375 2725) BN 27
J 0
(-3387 2733);
DISPLAY 0.489362 (-3387 2733);
PAINT GREEN (-3387 2733);
FORCEPROP 2 LAST CDS_LIB mstr_standard
J 0
(-3325 2725);
DISPLAY 0.723404 (-3325 2725);
PAINT MONO (-3325 2725);
DISPLAY INVISIBLE (-3325 2725);
FORCEPROP 1 LAST BODY_TYPE PLUMBING
J 0
(-3325 2775);
DISPLAY 0.872340 (-3325 2775);
PAINT GREEN (-3325 2775);
DISPLAY INVISIBLE (-3325 2775);
FORCEPROP 1 LAST HDL_TAP TRUE
J 0
(-3000 2600);
DISPLAY 0.872340 (-3000 2600);
DISPLAY INVISIBLE (-3000 2600);
FORCEPROP 1 LAST PATH I222
J 0
(-3327 2725);
DISPLAY 0.872340 (-3327 2725);
PAINT GREEN (-3327 2725);
DISPLAY INVISIBLE (-3327 2725);
FORCEADD TAP..1
(-3325 2675);
FORCEPROP 3 LASTPIN (-3375 2675) SIG_NAME M_D_CPU0_SB_DQ<28>
J 0
(-3365 2685);
DISPLAY 0.659574 (-3365 2685);
PAINT MONO (-3365 2685);
DISPLAY INVISIBLE (-3365 2685);
FORCEPROP 1 LASTPIN (-3375 2675) BN 28
J 0
(-3387 2683);
DISPLAY 0.489362 (-3387 2683);
PAINT GREEN (-3387 2683);
FORCEPROP 2 LAST CDS_LIB mstr_standard
J 0
(-3325 2675);
DISPLAY 0.723404 (-3325 2675);
PAINT MONO (-3325 2675);
DISPLAY INVISIBLE (-3325 2675);
FORCEPROP 1 LAST BODY_TYPE PLUMBING
J 0
(-3325 2725);
DISPLAY 0.872340 (-3325 2725);
PAINT GREEN (-3325 2725);
DISPLAY INVISIBLE (-3325 2725);
FORCEPROP 1 LAST HDL_TAP TRUE
J 0
(-3000 2550);
DISPLAY 0.872340 (-3000 2550);
DISPLAY INVISIBLE (-3000 2550);
FORCEPROP 1 LAST PATH I223
J 0
(-3327 2675);
DISPLAY 0.872340 (-3327 2675);
PAINT GREEN (-3327 2675);
DISPLAY INVISIBLE (-3327 2675);
FORCEADD TAP..1
(-3325 2575);
FORCEPROP 3 LASTPIN (-3375 2575) SIG_NAME M_D_CPU0_SB_DQ<30>
J 0
(-3365 2585);
DISPLAY 0.659574 (-3365 2585);
PAINT MONO (-3365 2585);
DISPLAY INVISIBLE (-3365 2585);
FORCEPROP 1 LASTPIN (-3375 2575) BN 30
J 0
(-3387 2583);
DISPLAY 0.489362 (-3387 2583);
PAINT GREEN (-3387 2583);
FORCEPROP 2 LAST CDS_LIB mstr_standard
J 0
(-3325 2575);
DISPLAY 0.723404 (-3325 2575);
PAINT MONO (-3325 2575);
DISPLAY INVISIBLE (-3325 2575);
FORCEPROP 1 LAST BODY_TYPE PLUMBING
J 0
(-3325 2625);
DISPLAY 0.872340 (-3325 2625);
PAINT GREEN (-3325 2625);
DISPLAY INVISIBLE (-3325 2625);
FORCEPROP 1 LAST HDL_TAP TRUE
J 0
(-3000 2450);
DISPLAY 0.872340 (-3000 2450);
DISPLAY INVISIBLE (-3000 2450);
FORCEPROP 1 LAST PATH I224
J 0
(-3327 2575);
DISPLAY 0.872340 (-3327 2575);
PAINT GREEN (-3327 2575);
DISPLAY INVISIBLE (-3327 2575);
FORCEADD TAP..1
(-3325 2625);
FORCEPROP 3 LASTPIN (-3375 2625) SIG_NAME M_D_CPU0_SB_DQ<29>
J 0
(-3365 2635);
DISPLAY 0.659574 (-3365 2635);
PAINT MONO (-3365 2635);
DISPLAY INVISIBLE (-3365 2635);
FORCEPROP 1 LASTPIN (-3375 2625) BN 29
J 0
(-3387 2633);
DISPLAY 0.489362 (-3387 2633);
PAINT GREEN (-3387 2633);
FORCEPROP 2 LAST CDS_LIB mstr_standard
J 0
(-3325 2625);
DISPLAY 0.723404 (-3325 2625);
PAINT MONO (-3325 2625);
DISPLAY INVISIBLE (-3325 2625);
FORCEPROP 1 LAST BODY_TYPE PLUMBING
J 0
(-3325 2675);
DISPLAY 0.872340 (-3325 2675);
PAINT GREEN (-3325 2675);
DISPLAY INVISIBLE (-3325 2675);
FORCEPROP 1 LAST HDL_TAP TRUE
J 0
(-3000 2500);
DISPLAY 0.872340 (-3000 2500);
DISPLAY INVISIBLE (-3000 2500);
FORCEPROP 1 LAST PATH I225
J 0
(-3327 2625);
DISPLAY 0.872340 (-3327 2625);
PAINT GREEN (-3327 2625);
DISPLAY INVISIBLE (-3327 2625);
FORCEADD TAP..1
(-3325 2325);
FORCEPROP 3 LASTPIN (-3375 2325) SIG_NAME M_D_CPU0_SA_CB<2>
J 0
(-3365 2335);
DISPLAY 0.659574 (-3365 2335);
PAINT MONO (-3365 2335);
DISPLAY INVISIBLE (-3365 2335);
FORCEPROP 1 LASTPIN (-3375 2325) BN 2
J 0
(-3387 2333);
DISPLAY 0.489362 (-3387 2333);
PAINT GREEN (-3387 2333);
FORCEPROP 2 LAST CDS_LIB mstr_standard
J 2
(-3325 2325);
DISPLAY 0.723404 (-3325 2325);
PAINT MONO (-3325 2325);
DISPLAY INVISIBLE (-3325 2325);
FORCEPROP 1 LAST BODY_TYPE PLUMBING
J 0
(-3325 2375);
DISPLAY 0.872340 (-3325 2375);
PAINT GREEN (-3325 2375);
DISPLAY INVISIBLE (-3325 2375);
FORCEPROP 1 LAST HDL_TAP TRUE
J 0
(-3000 2200);
DISPLAY 0.872340 (-3000 2200);
DISPLAY INVISIBLE (-3000 2200);
FORCEPROP 1 LAST PATH I226
J 0
(-3327 2325);
DISPLAY 0.872340 (-3327 2325);
PAINT GREEN (-3327 2325);
DISPLAY INVISIBLE (-3327 2325);
FORCEADD TAP..1
(-3325 2375);
FORCEPROP 3 LASTPIN (-3375 2375) SIG_NAME M_D_CPU0_SA_CB<1>
J 0
(-3365 2385);
DISPLAY 0.659574 (-3365 2385);
PAINT MONO (-3365 2385);
DISPLAY INVISIBLE (-3365 2385);
FORCEPROP 1 LASTPIN (-3375 2375) BN 1
J 0
(-3387 2383);
DISPLAY 0.489362 (-3387 2383);
PAINT GREEN (-3387 2383);
FORCEPROP 2 LAST CDS_LIB mstr_standard
J 2
(-3325 2375);
DISPLAY 0.723404 (-3325 2375);
PAINT MONO (-3325 2375);
DISPLAY INVISIBLE (-3325 2375);
FORCEPROP 1 LAST BODY_TYPE PLUMBING
J 0
(-3325 2425);
DISPLAY 0.872340 (-3325 2425);
PAINT GREEN (-3325 2425);
DISPLAY INVISIBLE (-3325 2425);
FORCEPROP 1 LAST HDL_TAP TRUE
J 0
(-3000 2250);
DISPLAY 0.872340 (-3000 2250);
DISPLAY INVISIBLE (-3000 2250);
FORCEPROP 1 LAST PATH I227
J 0
(-3327 2375);
DISPLAY 0.872340 (-3327 2375);
PAINT GREEN (-3327 2375);
DISPLAY INVISIBLE (-3327 2375);
FORCEADD TAP..1
(-3325 2425);
FORCEPROP 3 LASTPIN (-3375 2425) SIG_NAME M_D_CPU0_SA_CB<0>
J 0
(-3365 2435);
DISPLAY 0.659574 (-3365 2435);
PAINT MONO (-3365 2435);
DISPLAY INVISIBLE (-3365 2435);
FORCEPROP 1 LASTPIN (-3375 2425) BN 0
J 0
(-3387 2433);
DISPLAY 0.489362 (-3387 2433);
PAINT GREEN (-3387 2433);
FORCEPROP 2 LAST CDS_LIB mstr_standard
J 2
(-3325 2425);
DISPLAY 0.723404 (-3325 2425);
PAINT MONO (-3325 2425);
DISPLAY INVISIBLE (-3325 2425);
FORCEPROP 1 LAST BODY_TYPE PLUMBING
J 0
(-3325 2475);
DISPLAY 0.872340 (-3325 2475);
PAINT GREEN (-3325 2475);
DISPLAY INVISIBLE (-3325 2475);
FORCEPROP 1 LAST HDL_TAP TRUE
J 0
(-3000 2300);
DISPLAY 0.872340 (-3000 2300);
DISPLAY INVISIBLE (-3000 2300);
FORCEPROP 1 LAST PATH I228
J 0
(-3327 2425);
DISPLAY 0.872340 (-3327 2425);
PAINT GREEN (-3327 2425);
DISPLAY INVISIBLE (-3327 2425);
FORCEADD TAP..1
(-3325 2525);
FORCEPROP 3 LASTPIN (-3375 2525) SIG_NAME M_D_CPU0_SB_DQ<31>
J 0
(-3365 2535);
DISPLAY 0.659574 (-3365 2535);
PAINT MONO (-3365 2535);
DISPLAY INVISIBLE (-3365 2535);
FORCEPROP 1 LASTPIN (-3375 2525) BN 31
J 0
(-3387 2533);
DISPLAY 0.489362 (-3387 2533);
PAINT GREEN (-3387 2533);
FORCEPROP 2 LAST CDS_LIB mstr_standard
J 0
(-3325 2525);
DISPLAY 0.723404 (-3325 2525);
PAINT MONO (-3325 2525);
DISPLAY INVISIBLE (-3325 2525);
FORCEPROP 1 LAST BODY_TYPE PLUMBING
J 0
(-3325 2575);
DISPLAY 0.872340 (-3325 2575);
PAINT GREEN (-3325 2575);
DISPLAY INVISIBLE (-3325 2575);
FORCEPROP 1 LAST HDL_TAP TRUE
J 0
(-3000 2400);
DISPLAY 0.872340 (-3000 2400);
DISPLAY INVISIBLE (-3000 2400);
FORCEPROP 1 LAST PATH I229
J 0
(-3327 2525);
DISPLAY 0.872340 (-3327 2525);
PAINT GREEN (-3327 2525);
DISPLAY INVISIBLE (-3327 2525);
FORCEADD TAP..1
(-3325 2225);
FORCEPROP 3 LASTPIN (-3375 2225) SIG_NAME M_D_CPU0_SA_CB<4>
J 0
(-3365 2235);
DISPLAY 0.659574 (-3365 2235);
PAINT MONO (-3365 2235);
DISPLAY INVISIBLE (-3365 2235);
FORCEPROP 1 LASTPIN (-3375 2225) BN 4
J 0
(-3387 2233);
DISPLAY 0.489362 (-3387 2233);
PAINT GREEN (-3387 2233);
FORCEPROP 2 LAST CDS_LIB mstr_standard
J 2
(-3325 2225);
DISPLAY 0.723404 (-3325 2225);
PAINT MONO (-3325 2225);
DISPLAY INVISIBLE (-3325 2225);
FORCEPROP 1 LAST BODY_TYPE PLUMBING
J 0
(-3325 2275);
DISPLAY 0.872340 (-3325 2275);
PAINT GREEN (-3325 2275);
DISPLAY INVISIBLE (-3325 2275);
FORCEPROP 1 LAST HDL_TAP TRUE
J 0
(-3000 2100);
DISPLAY 0.872340 (-3000 2100);
DISPLAY INVISIBLE (-3000 2100);
FORCEPROP 1 LAST PATH I230
J 0
(-3327 2225);
DISPLAY 0.872340 (-3327 2225);
PAINT GREEN (-3327 2225);
DISPLAY INVISIBLE (-3327 2225);
FORCEADD TAP..1
(-3325 2275);
FORCEPROP 3 LASTPIN (-3375 2275) SIG_NAME M_D_CPU0_SA_CB<3>
J 0
(-3365 2285);
DISPLAY 0.659574 (-3365 2285);
PAINT MONO (-3365 2285);
DISPLAY INVISIBLE (-3365 2285);
FORCEPROP 1 LASTPIN (-3375 2275) BN 3
J 0
(-3387 2283);
DISPLAY 0.489362 (-3387 2283);
PAINT GREEN (-3387 2283);
FORCEPROP 2 LAST CDS_LIB mstr_standard
J 2
(-3325 2275);
DISPLAY 0.723404 (-3325 2275);
PAINT MONO (-3325 2275);
DISPLAY INVISIBLE (-3325 2275);
FORCEPROP 1 LAST BODY_TYPE PLUMBING
J 0
(-3325 2325);
DISPLAY 0.872340 (-3325 2325);
PAINT GREEN (-3325 2325);
DISPLAY INVISIBLE (-3325 2325);
FORCEPROP 1 LAST HDL_TAP TRUE
J 0
(-3000 2150);
DISPLAY 0.872340 (-3000 2150);
DISPLAY INVISIBLE (-3000 2150);
FORCEPROP 1 LAST PATH I231
J 0
(-3327 2275);
DISPLAY 0.872340 (-3327 2275);
PAINT GREEN (-3327 2275);
DISPLAY INVISIBLE (-3327 2275);
FORCEADD TAP..1
(-3325 2175);
FORCEPROP 3 LASTPIN (-3375 2175) SIG_NAME M_D_CPU0_SA_CB<5>
J 0
(-3365 2185);
DISPLAY 0.659574 (-3365 2185);
PAINT MONO (-3365 2185);
DISPLAY INVISIBLE (-3365 2185);
FORCEPROP 1 LASTPIN (-3375 2175) BN 5
J 0
(-3387 2183);
DISPLAY 0.489362 (-3387 2183);
PAINT GREEN (-3387 2183);
FORCEPROP 2 LAST CDS_LIB mstr_standard
J 2
(-3325 2175);
DISPLAY 0.723404 (-3325 2175);
PAINT MONO (-3325 2175);
DISPLAY INVISIBLE (-3325 2175);
FORCEPROP 1 LAST BODY_TYPE PLUMBING
J 0
(-3325 2225);
DISPLAY 0.872340 (-3325 2225);
PAINT GREEN (-3325 2225);
DISPLAY INVISIBLE (-3325 2225);
FORCEPROP 1 LAST HDL_TAP TRUE
J 0
(-3000 2050);
DISPLAY 0.872340 (-3000 2050);
DISPLAY INVISIBLE (-3000 2050);
FORCEPROP 1 LAST PATH I232
J 0
(-3327 2175);
DISPLAY 0.872340 (-3327 2175);
PAINT GREEN (-3327 2175);
DISPLAY INVISIBLE (-3327 2175);
FORCEADD TAP..1
(-3325 2125);
FORCEPROP 3 LASTPIN (-3375 2125) SIG_NAME M_D_CPU0_SA_CB<6>
J 0
(-3365 2135);
DISPLAY 0.659574 (-3365 2135);
PAINT MONO (-3365 2135);
DISPLAY INVISIBLE (-3365 2135);
FORCEPROP 1 LASTPIN (-3375 2125) BN 6
J 0
(-3387 2133);
DISPLAY 0.489362 (-3387 2133);
PAINT GREEN (-3387 2133);
FORCEPROP 2 LAST CDS_LIB mstr_standard
J 2
(-3325 2125);
DISPLAY 0.723404 (-3325 2125);
PAINT MONO (-3325 2125);
DISPLAY INVISIBLE (-3325 2125);
FORCEPROP 1 LAST BODY_TYPE PLUMBING
J 0
(-3325 2175);
DISPLAY 0.872340 (-3325 2175);
PAINT GREEN (-3325 2175);
DISPLAY INVISIBLE (-3325 2175);
FORCEPROP 1 LAST HDL_TAP TRUE
J 0
(-3000 2000);
DISPLAY 0.872340 (-3000 2000);
DISPLAY INVISIBLE (-3000 2000);
FORCEPROP 1 LAST PATH I233
J 0
(-3327 2125);
DISPLAY 0.872340 (-3327 2125);
PAINT GREEN (-3327 2125);
DISPLAY INVISIBLE (-3327 2125);
FORCEADD TAP..1
(-3325 2075);
FORCEPROP 3 LASTPIN (-3375 2075) SIG_NAME M_D_CPU0_SA_CB<7>
J 0
(-3365 2085);
DISPLAY 0.659574 (-3365 2085);
PAINT MONO (-3365 2085);
DISPLAY INVISIBLE (-3365 2085);
FORCEPROP 1 LASTPIN (-3375 2075) BN 7
J 0
(-3387 2083);
DISPLAY 0.489362 (-3387 2083);
PAINT GREEN (-3387 2083);
FORCEPROP 2 LAST CDS_LIB mstr_standard
J 2
(-3325 2075);
DISPLAY 0.723404 (-3325 2075);
PAINT MONO (-3325 2075);
DISPLAY INVISIBLE (-3325 2075);
FORCEPROP 1 LAST BODY_TYPE PLUMBING
J 0
(-3325 2125);
DISPLAY 0.872340 (-3325 2125);
PAINT GREEN (-3325 2125);
DISPLAY INVISIBLE (-3325 2125);
FORCEPROP 1 LAST HDL_TAP TRUE
J 0
(-3000 1950);
DISPLAY 0.872340 (-3000 1950);
DISPLAY INVISIBLE (-3000 1950);
FORCEPROP 1 LAST PATH I234
J 0
(-3327 2075);
DISPLAY 0.872340 (-3327 2075);
PAINT GREEN (-3327 2075);
DISPLAY INVISIBLE (-3327 2075);
FORCEADD OFFPAGE..6
R 2
(-2725 2025);
FORCEPROP 2 LAST $XR0 89 
J 0
(-2511 2025);
DISPLAY 0.638298 (-2511 2025);
PAINT MONO (-2511 2025);
FORCEPROP 2 LAST CDS_LIB mstr_standard
J 2
(-2725 2025);
DISPLAY 0.723404 (-2725 2025);
PAINT MONO (-2725 2025);
DISPLAY INVISIBLE (-2725 2025);
FORCEPROP 1 LAST OFFPAGE TRUE
J 2
(-3050 1900);
DISPLAY 0.872340 (-3050 1900);
PAINT GREEN (-3050 1900);
DISPLAY INVISIBLE (-3050 1900);
FORCEPROP 1 LAST COMMENT_BODY TRUE
J 2
(-2825 1950);
DISPLAY 0.872340 (-2825 1950);
PAINT GREEN (-2825 1950);
DISPLAY INVISIBLE (-2825 1950);
FORCEPROP 2 LAST PATH I235
J 0
(-2500 2075);
DISPLAY 1.021277 (-2500 2075);
DISPLAY INVISIBLE (-2500 2075);
FORCEADD TAP..1
(-3325 1825);
FORCEPROP 3 LASTPIN (-3375 1825) SIG_NAME M_D_CPU0_SB_CB<3>
J 0
(-3365 1835);
DISPLAY 0.659574 (-3365 1835);
PAINT MONO (-3365 1835);
DISPLAY INVISIBLE (-3365 1835);
FORCEPROP 1 LASTPIN (-3375 1825) BN 3
J 0
(-3387 1833);
DISPLAY 0.489362 (-3387 1833);
PAINT GREEN (-3387 1833);
FORCEPROP 2 LAST CDS_LIB mstr_standard
J 2
(-3325 1825);
DISPLAY 0.723404 (-3325 1825);
PAINT MONO (-3325 1825);
DISPLAY INVISIBLE (-3325 1825);
FORCEPROP 1 LAST BODY_TYPE PLUMBING
J 0
(-3325 1875);
DISPLAY 0.872340 (-3325 1875);
PAINT GREEN (-3325 1875);
DISPLAY INVISIBLE (-3325 1875);
FORCEPROP 1 LAST HDL_TAP TRUE
J 0
(-3000 1700);
DISPLAY 0.872340 (-3000 1700);
DISPLAY INVISIBLE (-3000 1700);
FORCEPROP 1 LAST PATH I236
J 0
(-3327 1825);
DISPLAY 0.872340 (-3327 1825);
PAINT GREEN (-3327 1825);
DISPLAY INVISIBLE (-3327 1825);
FORCEADD TAP..1
(-3325 1875);
FORCEPROP 3 LASTPIN (-3375 1875) SIG_NAME M_D_CPU0_SB_CB<2>
J 0
(-3365 1885);
DISPLAY 0.659574 (-3365 1885);
PAINT MONO (-3365 1885);
DISPLAY INVISIBLE (-3365 1885);
FORCEPROP 1 LASTPIN (-3375 1875) BN 2
J 0
(-3387 1883);
DISPLAY 0.489362 (-3387 1883);
PAINT GREEN (-3387 1883);
FORCEPROP 2 LAST CDS_LIB mstr_standard
J 2
(-3325 1875);
DISPLAY 0.723404 (-3325 1875);
PAINT MONO (-3325 1875);
DISPLAY INVISIBLE (-3325 1875);
FORCEPROP 1 LAST BODY_TYPE PLUMBING
J 0
(-3325 1925);
DISPLAY 0.872340 (-3325 1925);
PAINT GREEN (-3325 1925);
DISPLAY INVISIBLE (-3325 1925);
FORCEPROP 1 LAST HDL_TAP TRUE
J 0
(-3000 1750);
DISPLAY 0.872340 (-3000 1750);
DISPLAY INVISIBLE (-3000 1750);
FORCEPROP 1 LAST PATH I237
J 0
(-3327 1875);
DISPLAY 0.872340 (-3327 1875);
PAINT GREEN (-3327 1875);
DISPLAY INVISIBLE (-3327 1875);
FORCEADD TAP..1
(-3325 1975);
FORCEPROP 3 LASTPIN (-3375 1975) SIG_NAME M_D_CPU0_SB_CB<0>
J 0
(-3365 1985);
DISPLAY 0.659574 (-3365 1985);
PAINT MONO (-3365 1985);
DISPLAY INVISIBLE (-3365 1985);
FORCEPROP 1 LASTPIN (-3375 1975) BN 0
J 0
(-3387 1983);
DISPLAY 0.489362 (-3387 1983);
PAINT GREEN (-3387 1983);
FORCEPROP 2 LAST CDS_LIB mstr_standard
J 2
(-3325 1975);
DISPLAY 0.723404 (-3325 1975);
PAINT MONO (-3325 1975);
DISPLAY INVISIBLE (-3325 1975);
FORCEPROP 1 LAST BODY_TYPE PLUMBING
J 0
(-3325 2025);
DISPLAY 0.872340 (-3325 2025);
PAINT GREEN (-3325 2025);
DISPLAY INVISIBLE (-3325 2025);
FORCEPROP 1 LAST HDL_TAP TRUE
J 0
(-3000 1850);
DISPLAY 0.872340 (-3000 1850);
DISPLAY INVISIBLE (-3000 1850);
FORCEPROP 1 LAST PATH I238
J 0
(-3327 1975);
DISPLAY 0.872340 (-3327 1975);
PAINT GREEN (-3327 1975);
DISPLAY INVISIBLE (-3327 1975);
FORCEADD TAP..1
(-3325 1925);
FORCEPROP 3 LASTPIN (-3375 1925) SIG_NAME M_D_CPU0_SB_CB<1>
J 0
(-3365 1935);
DISPLAY 0.659574 (-3365 1935);
PAINT MONO (-3365 1935);
DISPLAY INVISIBLE (-3365 1935);
FORCEPROP 1 LASTPIN (-3375 1925) BN 1
J 0
(-3387 1933);
DISPLAY 0.489362 (-3387 1933);
PAINT GREEN (-3387 1933);
FORCEPROP 2 LAST CDS_LIB mstr_standard
J 2
(-3325 1925);
DISPLAY 0.723404 (-3325 1925);
PAINT MONO (-3325 1925);
DISPLAY INVISIBLE (-3325 1925);
FORCEPROP 1 LAST BODY_TYPE PLUMBING
J 0
(-3325 1975);
DISPLAY 0.872340 (-3325 1975);
PAINT GREEN (-3325 1975);
DISPLAY INVISIBLE (-3325 1975);
FORCEPROP 1 LAST HDL_TAP TRUE
J 0
(-3000 1800);
DISPLAY 0.872340 (-3000 1800);
DISPLAY INVISIBLE (-3000 1800);
FORCEPROP 1 LAST PATH I239
J 0
(-3327 1925);
DISPLAY 0.872340 (-3327 1925);
PAINT GREEN (-3327 1925);
DISPLAY INVISIBLE (-3327 1925);
FORCEADD TAP..1
(-3325 1675);
FORCEPROP 3 LASTPIN (-3375 1675) SIG_NAME M_D_CPU0_SB_CB<6>
J 0
(-3365 1685);
DISPLAY 0.659574 (-3365 1685);
PAINT MONO (-3365 1685);
DISPLAY INVISIBLE (-3365 1685);
FORCEPROP 1 LASTPIN (-3375 1675) BN 6
J 0
(-3387 1683);
DISPLAY 0.489362 (-3387 1683);
PAINT GREEN (-3387 1683);
FORCEPROP 2 LAST CDS_LIB mstr_standard
J 2
(-3325 1675);
DISPLAY 0.723404 (-3325 1675);
PAINT MONO (-3325 1675);
DISPLAY INVISIBLE (-3325 1675);
FORCEPROP 1 LAST BODY_TYPE PLUMBING
J 0
(-3325 1725);
DISPLAY 0.872340 (-3325 1725);
PAINT GREEN (-3325 1725);
DISPLAY INVISIBLE (-3325 1725);
FORCEPROP 1 LAST HDL_TAP TRUE
J 0
(-3000 1550);
DISPLAY 0.872340 (-3000 1550);
DISPLAY INVISIBLE (-3000 1550);
FORCEPROP 1 LAST PATH I240
J 0
(-3327 1675);
DISPLAY 0.872340 (-3327 1675);
PAINT GREEN (-3327 1675);
DISPLAY INVISIBLE (-3327 1675);
FORCEADD TAP..1
(-3325 1775);
FORCEPROP 3 LASTPIN (-3375 1775) SIG_NAME M_D_CPU0_SB_CB<4>
J 0
(-3365 1785);
DISPLAY 0.659574 (-3365 1785);
PAINT MONO (-3365 1785);
DISPLAY INVISIBLE (-3365 1785);
FORCEPROP 1 LASTPIN (-3375 1775) BN 4
J 0
(-3387 1783);
DISPLAY 0.489362 (-3387 1783);
PAINT GREEN (-3387 1783);
FORCEPROP 2 LAST CDS_LIB mstr_standard
J 2
(-3325 1775);
DISPLAY 0.723404 (-3325 1775);
PAINT MONO (-3325 1775);
DISPLAY INVISIBLE (-3325 1775);
FORCEPROP 1 LAST BODY_TYPE PLUMBING
J 0
(-3325 1825);
DISPLAY 0.872340 (-3325 1825);
PAINT GREEN (-3325 1825);
DISPLAY INVISIBLE (-3325 1825);
FORCEPROP 1 LAST HDL_TAP TRUE
J 0
(-3000 1650);
DISPLAY 0.872340 (-3000 1650);
DISPLAY INVISIBLE (-3000 1650);
FORCEPROP 1 LAST PATH I241
J 0
(-3327 1775);
DISPLAY 0.872340 (-3327 1775);
PAINT GREEN (-3327 1775);
DISPLAY INVISIBLE (-3327 1775);
FORCEADD TAP..1
(-3325 1725);
FORCEPROP 3 LASTPIN (-3375 1725) SIG_NAME M_D_CPU0_SB_CB<5>
J 0
(-3365 1735);
DISPLAY 0.659574 (-3365 1735);
PAINT MONO (-3365 1735);
DISPLAY INVISIBLE (-3365 1735);
FORCEPROP 1 LASTPIN (-3375 1725) BN 5
J 0
(-3387 1733);
DISPLAY 0.489362 (-3387 1733);
PAINT GREEN (-3387 1733);
FORCEPROP 2 LAST CDS_LIB mstr_standard
J 2
(-3325 1725);
DISPLAY 0.723404 (-3325 1725);
PAINT MONO (-3325 1725);
DISPLAY INVISIBLE (-3325 1725);
FORCEPROP 1 LAST BODY_TYPE PLUMBING
J 0
(-3325 1775);
DISPLAY 0.872340 (-3325 1775);
PAINT GREEN (-3325 1775);
DISPLAY INVISIBLE (-3325 1775);
FORCEPROP 1 LAST HDL_TAP TRUE
J 0
(-3000 1600);
DISPLAY 0.872340 (-3000 1600);
DISPLAY INVISIBLE (-3000 1600);
FORCEPROP 1 LAST PATH I242
J 0
(-3327 1725);
DISPLAY 0.872340 (-3327 1725);
PAINT GREEN (-3327 1725);
DISPLAY INVISIBLE (-3327 1725);
FORCEADD TAP..1
(-3325 1625);
FORCEPROP 3 LASTPIN (-3375 1625) SIG_NAME M_D_CPU0_SB_CB<7>
J 0
(-3365 1635);
DISPLAY 0.659574 (-3365 1635);
PAINT MONO (-3365 1635);
DISPLAY INVISIBLE (-3365 1635);
FORCEPROP 1 LASTPIN (-3375 1625) BN 7
J 0
(-3387 1633);
DISPLAY 0.489362 (-3387 1633);
PAINT GREEN (-3387 1633);
FORCEPROP 2 LAST CDS_LIB mstr_standard
J 2
(-3325 1625);
DISPLAY 0.723404 (-3325 1625);
PAINT MONO (-3325 1625);
DISPLAY INVISIBLE (-3325 1625);
FORCEPROP 1 LAST BODY_TYPE PLUMBING
J 0
(-3325 1675);
DISPLAY 0.872340 (-3325 1675);
PAINT GREEN (-3325 1675);
DISPLAY INVISIBLE (-3325 1675);
FORCEPROP 1 LAST HDL_TAP TRUE
J 0
(-3000 1500);
DISPLAY 0.872340 (-3000 1500);
DISPLAY INVISIBLE (-3000 1500);
FORCEPROP 1 LAST PATH I243
J 0
(-3327 1625);
DISPLAY 0.872340 (-3327 1625);
PAINT GREEN (-3327 1625);
DISPLAY INVISIBLE (-3327 1625);
FORCEADD TAP..1
R 2
(-5750 6025);
FORCEPROP 3 LASTPIN (-5700 6025) SIG_NAME M_D_CPU0_SA_DQS_DP<0>
J 0
(-5690 6035);
DISPLAY 0.659574 (-5690 6035);
PAINT MONO (-5690 6035);
DISPLAY INVISIBLE (-5690 6035);
FORCEPROP 1 LASTPIN (-5700 6025) BN 0
J 2
(-5688 6033);
DISPLAY 0.489362 (-5688 6033);
PAINT GREEN (-5688 6033);
FORCEPROP 2 LAST CDS_LIB mstr_standard
J 2
(-5750 6025);
DISPLAY 0.723404 (-5750 6025);
PAINT MONO (-5750 6025);
DISPLAY INVISIBLE (-5750 6025);
FORCEPROP 1 LAST BODY_TYPE PLUMBING
J 2
(-5750 6075);
DISPLAY 0.872340 (-5750 6075);
PAINT GREEN (-5750 6075);
DISPLAY INVISIBLE (-5750 6075);
FORCEPROP 1 LAST HDL_TAP TRUE
J 2
(-6075 5900);
DISPLAY 0.872340 (-6075 5900);
DISPLAY INVISIBLE (-6075 5900);
FORCEPROP 1 LAST PATH I244
J 2
(-5748 6025);
DISPLAY 0.872340 (-5748 6025);
PAINT GREEN (-5748 6025);
DISPLAY INVISIBLE (-5748 6025);
FORCEADD TAP..1
R 2
(-5750 5925);
FORCEPROP 3 LASTPIN (-5700 5925) SIG_NAME M_D_CPU0_SA_DQS_DP<1>
J 0
(-5690 5935);
DISPLAY 0.659574 (-5690 5935);
PAINT MONO (-5690 5935);
DISPLAY INVISIBLE (-5690 5935);
FORCEPROP 1 LASTPIN (-5700 5925) BN 1
J 2
(-5688 5933);
DISPLAY 0.489362 (-5688 5933);
PAINT GREEN (-5688 5933);
FORCEPROP 2 LAST CDS_LIB mstr_standard
J 2
(-5750 5925);
DISPLAY 0.723404 (-5750 5925);
PAINT MONO (-5750 5925);
DISPLAY INVISIBLE (-5750 5925);
FORCEPROP 1 LAST BODY_TYPE PLUMBING
J 2
(-5750 5975);
DISPLAY 0.872340 (-5750 5975);
PAINT GREEN (-5750 5975);
DISPLAY INVISIBLE (-5750 5975);
FORCEPROP 1 LAST HDL_TAP TRUE
J 2
(-6075 5800);
DISPLAY 0.872340 (-6075 5800);
DISPLAY INVISIBLE (-6075 5800);
FORCEPROP 1 LAST PATH I245
J 2
(-5748 5925);
DISPLAY 0.872340 (-5748 5925);
PAINT GREEN (-5748 5925);
DISPLAY INVISIBLE (-5748 5925);
FORCEADD TAP..1
R 2
(-5750 5825);
FORCEPROP 3 LASTPIN (-5700 5825) SIG_NAME M_D_CPU0_SA_DQS_DP<2>
J 0
(-5690 5835);
DISPLAY 0.659574 (-5690 5835);
PAINT MONO (-5690 5835);
DISPLAY INVISIBLE (-5690 5835);
FORCEPROP 1 LASTPIN (-5700 5825) BN 2
J 2
(-5688 5833);
DISPLAY 0.489362 (-5688 5833);
PAINT GREEN (-5688 5833);
FORCEPROP 2 LAST CDS_LIB mstr_standard
J 2
(-5750 5825);
DISPLAY 0.723404 (-5750 5825);
PAINT MONO (-5750 5825);
DISPLAY INVISIBLE (-5750 5825);
FORCEPROP 1 LAST BODY_TYPE PLUMBING
J 2
(-5750 5875);
DISPLAY 0.872340 (-5750 5875);
PAINT GREEN (-5750 5875);
DISPLAY INVISIBLE (-5750 5875);
FORCEPROP 1 LAST HDL_TAP TRUE
J 2
(-6075 5700);
DISPLAY 0.872340 (-6075 5700);
DISPLAY INVISIBLE (-6075 5700);
FORCEPROP 1 LAST PATH I246
J 2
(-5748 5825);
DISPLAY 0.872340 (-5748 5825);
PAINT GREEN (-5748 5825);
DISPLAY INVISIBLE (-5748 5825);
FORCEADD TAP..1
R 2
(-5750 5725);
FORCEPROP 3 LASTPIN (-5700 5725) SIG_NAME M_D_CPU0_SA_DQS_DP<3>
J 0
(-5690 5735);
DISPLAY 0.659574 (-5690 5735);
PAINT MONO (-5690 5735);
DISPLAY INVISIBLE (-5690 5735);
FORCEPROP 1 LASTPIN (-5700 5725) BN 3
J 2
(-5688 5733);
DISPLAY 0.489362 (-5688 5733);
PAINT GREEN (-5688 5733);
FORCEPROP 2 LAST CDS_LIB mstr_standard
J 2
(-5750 5725);
DISPLAY 0.723404 (-5750 5725);
PAINT MONO (-5750 5725);
DISPLAY INVISIBLE (-5750 5725);
FORCEPROP 1 LAST BODY_TYPE PLUMBING
J 2
(-5750 5775);
DISPLAY 0.872340 (-5750 5775);
PAINT GREEN (-5750 5775);
DISPLAY INVISIBLE (-5750 5775);
FORCEPROP 1 LAST HDL_TAP TRUE
J 2
(-6075 5600);
DISPLAY 0.872340 (-6075 5600);
DISPLAY INVISIBLE (-6075 5600);
FORCEPROP 1 LAST PATH I247
J 2
(-5748 5725);
DISPLAY 0.872340 (-5748 5725);
PAINT GREEN (-5748 5725);
DISPLAY INVISIBLE (-5748 5725);
FORCEADD TAP..1
R 2
(-5950 5975);
FORCEPROP 3 LASTPIN (-5900 5975) SIG_NAME M_D_CPU0_SA_DQS_DN<0>
J 0
(-5890 5985);
DISPLAY 0.659574 (-5890 5985);
PAINT MONO (-5890 5985);
DISPLAY INVISIBLE (-5890 5985);
FORCEPROP 1 LASTPIN (-5900 5975) BN 0
J 2
(-5888 5983);
DISPLAY 0.489362 (-5888 5983);
PAINT GREEN (-5888 5983);
FORCEPROP 2 LAST CDS_LIB mstr_standard
J 2
(-5950 5975);
DISPLAY 0.723404 (-5950 5975);
PAINT MONO (-5950 5975);
DISPLAY INVISIBLE (-5950 5975);
FORCEPROP 1 LAST BODY_TYPE PLUMBING
J 2
(-5950 6025);
DISPLAY 0.872340 (-5950 6025);
PAINT GREEN (-5950 6025);
DISPLAY INVISIBLE (-5950 6025);
FORCEPROP 1 LAST HDL_TAP TRUE
J 2
(-6275 5850);
DISPLAY 0.872340 (-6275 5850);
DISPLAY INVISIBLE (-6275 5850);
FORCEPROP 1 LAST PATH I248
J 2
(-5948 5975);
DISPLAY 0.872340 (-5948 5975);
PAINT GREEN (-5948 5975);
DISPLAY INVISIBLE (-5948 5975);
FORCEADD TAP..1
R 2
(-5950 5875);
FORCEPROP 3 LASTPIN (-5900 5875) SIG_NAME M_D_CPU0_SA_DQS_DN<1>
J 0
(-5890 5885);
DISPLAY 0.659574 (-5890 5885);
PAINT MONO (-5890 5885);
DISPLAY INVISIBLE (-5890 5885);
FORCEPROP 1 LASTPIN (-5900 5875) BN 1
J 2
(-5888 5883);
DISPLAY 0.489362 (-5888 5883);
PAINT GREEN (-5888 5883);
FORCEPROP 2 LAST CDS_LIB mstr_standard
J 2
(-5950 5875);
DISPLAY 0.723404 (-5950 5875);
PAINT MONO (-5950 5875);
DISPLAY INVISIBLE (-5950 5875);
FORCEPROP 1 LAST BODY_TYPE PLUMBING
J 2
(-5950 5925);
DISPLAY 0.872340 (-5950 5925);
PAINT GREEN (-5950 5925);
DISPLAY INVISIBLE (-5950 5925);
FORCEPROP 1 LAST HDL_TAP TRUE
J 2
(-6275 5750);
DISPLAY 0.872340 (-6275 5750);
DISPLAY INVISIBLE (-6275 5750);
FORCEPROP 1 LAST PATH I249
J 2
(-5948 5875);
DISPLAY 0.872340 (-5948 5875);
PAINT GREEN (-5948 5875);
DISPLAY INVISIBLE (-5948 5875);
FORCEADD TAP..1
R 2
(-5950 5775);
FORCEPROP 3 LASTPIN (-5900 5775) SIG_NAME M_D_CPU0_SA_DQS_DN<2>
J 0
(-5890 5785);
DISPLAY 0.659574 (-5890 5785);
PAINT MONO (-5890 5785);
DISPLAY INVISIBLE (-5890 5785);
FORCEPROP 1 LASTPIN (-5900 5775) BN 2
J 2
(-5888 5783);
DISPLAY 0.489362 (-5888 5783);
PAINT GREEN (-5888 5783);
FORCEPROP 2 LAST CDS_LIB mstr_standard
J 2
(-5950 5775);
DISPLAY 0.723404 (-5950 5775);
PAINT MONO (-5950 5775);
DISPLAY INVISIBLE (-5950 5775);
FORCEPROP 1 LAST BODY_TYPE PLUMBING
J 2
(-5950 5825);
DISPLAY 0.872340 (-5950 5825);
PAINT GREEN (-5950 5825);
DISPLAY INVISIBLE (-5950 5825);
FORCEPROP 1 LAST HDL_TAP TRUE
J 2
(-6275 5650);
DISPLAY 0.872340 (-6275 5650);
DISPLAY INVISIBLE (-6275 5650);
FORCEPROP 1 LAST PATH I250
J 2
(-5948 5775);
DISPLAY 0.872340 (-5948 5775);
PAINT GREEN (-5948 5775);
DISPLAY INVISIBLE (-5948 5775);
FORCEADD TAP..1
R 2
(-5950 5675);
FORCEPROP 3 LASTPIN (-5900 5675) SIG_NAME M_D_CPU0_SA_DQS_DN<3>
J 0
(-5890 5685);
DISPLAY 0.659574 (-5890 5685);
PAINT MONO (-5890 5685);
DISPLAY INVISIBLE (-5890 5685);
FORCEPROP 1 LASTPIN (-5900 5675) BN 3
J 2
(-5888 5683);
DISPLAY 0.489362 (-5888 5683);
PAINT GREEN (-5888 5683);
FORCEPROP 2 LAST CDS_LIB mstr_standard
J 2
(-5950 5675);
DISPLAY 0.723404 (-5950 5675);
PAINT MONO (-5950 5675);
DISPLAY INVISIBLE (-5950 5675);
FORCEPROP 1 LAST BODY_TYPE PLUMBING
J 2
(-5950 5725);
DISPLAY 0.872340 (-5950 5725);
PAINT GREEN (-5950 5725);
DISPLAY INVISIBLE (-5950 5725);
FORCEPROP 1 LAST HDL_TAP TRUE
J 2
(-6275 5550);
DISPLAY 0.872340 (-6275 5550);
DISPLAY INVISIBLE (-6275 5550);
FORCEPROP 1 LAST PATH I251
J 2
(-5948 5675);
DISPLAY 0.872340 (-5948 5675);
PAINT GREEN (-5948 5675);
DISPLAY INVISIBLE (-5948 5675);
FORCEADD TAP..1
R 2
(-5750 5525);
FORCEPROP 3 LASTPIN (-5700 5525) SIG_NAME M_D_CPU0_SA_DQS_DP<5>
J 0
(-5690 5535);
DISPLAY 0.659574 (-5690 5535);
PAINT MONO (-5690 5535);
DISPLAY INVISIBLE (-5690 5535);
FORCEPROP 1 LASTPIN (-5700 5525) BN 5
J 2
(-5688 5533);
DISPLAY 0.489362 (-5688 5533);
PAINT GREEN (-5688 5533);
FORCEPROP 2 LAST CDS_LIB mstr_standard
J 2
(-5750 5525);
DISPLAY 0.723404 (-5750 5525);
PAINT MONO (-5750 5525);
DISPLAY INVISIBLE (-5750 5525);
FORCEPROP 1 LAST BODY_TYPE PLUMBING
J 2
(-5750 5575);
DISPLAY 0.872340 (-5750 5575);
PAINT GREEN (-5750 5575);
DISPLAY INVISIBLE (-5750 5575);
FORCEPROP 1 LAST HDL_TAP TRUE
J 2
(-6075 5400);
DISPLAY 0.872340 (-6075 5400);
DISPLAY INVISIBLE (-6075 5400);
FORCEPROP 1 LAST PATH I252
J 2
(-5748 5525);
DISPLAY 0.872340 (-5748 5525);
PAINT GREEN (-5748 5525);
DISPLAY INVISIBLE (-5748 5525);
FORCEADD TAP..1
R 2
(-5750 5625);
FORCEPROP 3 LASTPIN (-5700 5625) SIG_NAME M_D_CPU0_SA_DQS_DP<4>
J 0
(-5690 5635);
DISPLAY 0.659574 (-5690 5635);
PAINT MONO (-5690 5635);
DISPLAY INVISIBLE (-5690 5635);
FORCEPROP 1 LASTPIN (-5700 5625) BN 4
J 2
(-5688 5633);
DISPLAY 0.489362 (-5688 5633);
PAINT GREEN (-5688 5633);
FORCEPROP 2 LAST CDS_LIB mstr_standard
J 2
(-5750 5625);
DISPLAY 0.723404 (-5750 5625);
PAINT MONO (-5750 5625);
DISPLAY INVISIBLE (-5750 5625);
FORCEPROP 1 LAST BODY_TYPE PLUMBING
J 2
(-5750 5675);
DISPLAY 0.872340 (-5750 5675);
PAINT GREEN (-5750 5675);
DISPLAY INVISIBLE (-5750 5675);
FORCEPROP 1 LAST HDL_TAP TRUE
J 2
(-6075 5500);
DISPLAY 0.872340 (-6075 5500);
DISPLAY INVISIBLE (-6075 5500);
FORCEPROP 1 LAST PATH I253
J 2
(-5748 5625);
DISPLAY 0.872340 (-5748 5625);
PAINT GREEN (-5748 5625);
DISPLAY INVISIBLE (-5748 5625);
FORCEADD TAP..1
R 2
(-5750 5425);
FORCEPROP 3 LASTPIN (-5700 5425) SIG_NAME M_D_CPU0_SA_DQS_DP<6>
J 0
(-5690 5435);
DISPLAY 0.659574 (-5690 5435);
PAINT MONO (-5690 5435);
DISPLAY INVISIBLE (-5690 5435);
FORCEPROP 1 LASTPIN (-5700 5425) BN 6
J 2
(-5688 5433);
DISPLAY 0.489362 (-5688 5433);
PAINT GREEN (-5688 5433);
FORCEPROP 2 LAST CDS_LIB mstr_standard
J 2
(-5750 5425);
DISPLAY 0.723404 (-5750 5425);
PAINT MONO (-5750 5425);
DISPLAY INVISIBLE (-5750 5425);
FORCEPROP 1 LAST BODY_TYPE PLUMBING
J 2
(-5750 5475);
DISPLAY 0.872340 (-5750 5475);
PAINT GREEN (-5750 5475);
DISPLAY INVISIBLE (-5750 5475);
FORCEPROP 1 LAST HDL_TAP TRUE
J 2
(-6075 5300);
DISPLAY 0.872340 (-6075 5300);
DISPLAY INVISIBLE (-6075 5300);
FORCEPROP 1 LAST PATH I254
J 2
(-5748 5425);
DISPLAY 0.872340 (-5748 5425);
PAINT GREEN (-5748 5425);
DISPLAY INVISIBLE (-5748 5425);
FORCEADD TAP..1
R 2
(-5750 5325);
FORCEPROP 3 LASTPIN (-5700 5325) SIG_NAME M_D_CPU0_SA_DQS_DP<7>
J 0
(-5690 5335);
DISPLAY 0.659574 (-5690 5335);
PAINT MONO (-5690 5335);
DISPLAY INVISIBLE (-5690 5335);
FORCEPROP 1 LASTPIN (-5700 5325) BN 7
J 2
(-5688 5333);
DISPLAY 0.489362 (-5688 5333);
PAINT GREEN (-5688 5333);
FORCEPROP 2 LAST CDS_LIB mstr_standard
J 2
(-5750 5325);
DISPLAY 0.723404 (-5750 5325);
PAINT MONO (-5750 5325);
DISPLAY INVISIBLE (-5750 5325);
FORCEPROP 1 LAST BODY_TYPE PLUMBING
J 2
(-5750 5375);
DISPLAY 0.872340 (-5750 5375);
PAINT GREEN (-5750 5375);
DISPLAY INVISIBLE (-5750 5375);
FORCEPROP 1 LAST HDL_TAP TRUE
J 2
(-6075 5200);
DISPLAY 0.872340 (-6075 5200);
DISPLAY INVISIBLE (-6075 5200);
FORCEPROP 1 LAST PATH I255
J 2
(-5748 5325);
DISPLAY 0.872340 (-5748 5325);
PAINT GREEN (-5748 5325);
DISPLAY INVISIBLE (-5748 5325);
FORCEADD TAP..1
R 2
(-5750 5125);
FORCEPROP 3 LASTPIN (-5700 5125) SIG_NAME M_D_CPU0_SA_DQS_DP<9>
J 0
(-5690 5135);
DISPLAY 0.659574 (-5690 5135);
PAINT MONO (-5690 5135);
DISPLAY INVISIBLE (-5690 5135);
FORCEPROP 1 LASTPIN (-5700 5125) BN 9
J 2
(-5688 5133);
DISPLAY 0.489362 (-5688 5133);
PAINT GREEN (-5688 5133);
FORCEPROP 2 LAST CDS_LIB mstr_standard
J 2
(-5750 5125);
DISPLAY 0.723404 (-5750 5125);
PAINT MONO (-5750 5125);
DISPLAY INVISIBLE (-5750 5125);
FORCEPROP 1 LAST BODY_TYPE PLUMBING
J 2
(-5750 5175);
DISPLAY 0.872340 (-5750 5175);
PAINT GREEN (-5750 5175);
DISPLAY INVISIBLE (-5750 5175);
FORCEPROP 1 LAST HDL_TAP TRUE
J 2
(-6075 5000);
DISPLAY 0.872340 (-6075 5000);
DISPLAY INVISIBLE (-6075 5000);
FORCEPROP 1 LAST PATH I256
J 2
(-5748 5125);
DISPLAY 0.872340 (-5748 5125);
PAINT GREEN (-5748 5125);
DISPLAY INVISIBLE (-5748 5125);
FORCEADD TAP..1
R 2
(-5750 5225);
FORCEPROP 3 LASTPIN (-5700 5225) SIG_NAME M_D_CPU0_SA_DQS_DP<8>
J 0
(-5690 5235);
DISPLAY 0.659574 (-5690 5235);
PAINT MONO (-5690 5235);
DISPLAY INVISIBLE (-5690 5235);
FORCEPROP 1 LASTPIN (-5700 5225) BN 8
J 2
(-5688 5233);
DISPLAY 0.489362 (-5688 5233);
PAINT GREEN (-5688 5233);
FORCEPROP 2 LAST CDS_LIB mstr_standard
J 2
(-5750 5225);
DISPLAY 0.723404 (-5750 5225);
PAINT MONO (-5750 5225);
DISPLAY INVISIBLE (-5750 5225);
FORCEPROP 1 LAST BODY_TYPE PLUMBING
J 2
(-5750 5275);
DISPLAY 0.872340 (-5750 5275);
PAINT GREEN (-5750 5275);
DISPLAY INVISIBLE (-5750 5275);
FORCEPROP 1 LAST HDL_TAP TRUE
J 2
(-6075 5100);
DISPLAY 0.872340 (-6075 5100);
DISPLAY INVISIBLE (-6075 5100);
FORCEPROP 1 LAST PATH I257
J 2
(-5748 5225);
DISPLAY 0.872340 (-5748 5225);
PAINT GREEN (-5748 5225);
DISPLAY INVISIBLE (-5748 5225);
FORCEADD TAP..1
R 2
(-5950 5575);
FORCEPROP 3 LASTPIN (-5900 5575) SIG_NAME M_D_CPU0_SA_DQS_DN<4>
J 0
(-5890 5585);
DISPLAY 0.659574 (-5890 5585);
PAINT MONO (-5890 5585);
DISPLAY INVISIBLE (-5890 5585);
FORCEPROP 1 LASTPIN (-5900 5575) BN 4
J 2
(-5888 5583);
DISPLAY 0.489362 (-5888 5583);
PAINT GREEN (-5888 5583);
FORCEPROP 2 LAST CDS_LIB mstr_standard
J 2
(-5950 5575);
DISPLAY 0.723404 (-5950 5575);
PAINT MONO (-5950 5575);
DISPLAY INVISIBLE (-5950 5575);
FORCEPROP 1 LAST BODY_TYPE PLUMBING
J 2
(-5950 5625);
DISPLAY 0.872340 (-5950 5625);
PAINT GREEN (-5950 5625);
DISPLAY INVISIBLE (-5950 5625);
FORCEPROP 1 LAST HDL_TAP TRUE
J 2
(-6275 5450);
DISPLAY 0.872340 (-6275 5450);
DISPLAY INVISIBLE (-6275 5450);
FORCEPROP 1 LAST PATH I258
J 2
(-5948 5575);
DISPLAY 0.872340 (-5948 5575);
PAINT GREEN (-5948 5575);
DISPLAY INVISIBLE (-5948 5575);
FORCEADD TAP..1
R 2
(-5950 5475);
FORCEPROP 3 LASTPIN (-5900 5475) SIG_NAME M_D_CPU0_SA_DQS_DN<5>
J 0
(-5890 5485);
DISPLAY 0.659574 (-5890 5485);
PAINT MONO (-5890 5485);
DISPLAY INVISIBLE (-5890 5485);
FORCEPROP 1 LASTPIN (-5900 5475) BN 5
J 2
(-5888 5483);
DISPLAY 0.489362 (-5888 5483);
PAINT GREEN (-5888 5483);
FORCEPROP 2 LAST CDS_LIB mstr_standard
J 2
(-5950 5475);
DISPLAY 0.723404 (-5950 5475);
PAINT MONO (-5950 5475);
DISPLAY INVISIBLE (-5950 5475);
FORCEPROP 1 LAST BODY_TYPE PLUMBING
J 2
(-5950 5525);
DISPLAY 0.872340 (-5950 5525);
PAINT GREEN (-5950 5525);
DISPLAY INVISIBLE (-5950 5525);
FORCEPROP 1 LAST HDL_TAP TRUE
J 2
(-6275 5350);
DISPLAY 0.872340 (-6275 5350);
DISPLAY INVISIBLE (-6275 5350);
FORCEPROP 1 LAST PATH I259
J 2
(-5948 5475);
DISPLAY 0.872340 (-5948 5475);
PAINT GREEN (-5948 5475);
DISPLAY INVISIBLE (-5948 5475);
FORCEADD TAP..1
R 2
(-5950 5375);
FORCEPROP 3 LASTPIN (-5900 5375) SIG_NAME M_D_CPU0_SA_DQS_DN<6>
J 0
(-5890 5385);
DISPLAY 0.659574 (-5890 5385);
PAINT MONO (-5890 5385);
DISPLAY INVISIBLE (-5890 5385);
FORCEPROP 1 LASTPIN (-5900 5375) BN 6
J 2
(-5888 5383);
DISPLAY 0.489362 (-5888 5383);
PAINT GREEN (-5888 5383);
FORCEPROP 2 LAST CDS_LIB mstr_standard
J 2
(-5950 5375);
DISPLAY 0.723404 (-5950 5375);
PAINT MONO (-5950 5375);
DISPLAY INVISIBLE (-5950 5375);
FORCEPROP 1 LAST BODY_TYPE PLUMBING
J 2
(-5950 5425);
DISPLAY 0.872340 (-5950 5425);
PAINT GREEN (-5950 5425);
DISPLAY INVISIBLE (-5950 5425);
FORCEPROP 1 LAST HDL_TAP TRUE
J 2
(-6275 5250);
DISPLAY 0.872340 (-6275 5250);
DISPLAY INVISIBLE (-6275 5250);
FORCEPROP 1 LAST PATH I260
J 2
(-5948 5375);
DISPLAY 0.872340 (-5948 5375);
PAINT GREEN (-5948 5375);
DISPLAY INVISIBLE (-5948 5375);
FORCEADD TAP..1
R 2
(-5950 5275);
FORCEPROP 3 LASTPIN (-5900 5275) SIG_NAME M_D_CPU0_SA_DQS_DN<7>
J 0
(-5890 5285);
DISPLAY 0.659574 (-5890 5285);
PAINT MONO (-5890 5285);
DISPLAY INVISIBLE (-5890 5285);
FORCEPROP 1 LASTPIN (-5900 5275) BN 7
J 2
(-5888 5283);
DISPLAY 0.489362 (-5888 5283);
PAINT GREEN (-5888 5283);
FORCEPROP 2 LAST CDS_LIB mstr_standard
J 2
(-5950 5275);
DISPLAY 0.723404 (-5950 5275);
PAINT MONO (-5950 5275);
DISPLAY INVISIBLE (-5950 5275);
FORCEPROP 1 LAST BODY_TYPE PLUMBING
J 2
(-5950 5325);
DISPLAY 0.872340 (-5950 5325);
PAINT GREEN (-5950 5325);
DISPLAY INVISIBLE (-5950 5325);
FORCEPROP 1 LAST HDL_TAP TRUE
J 2
(-6275 5150);
DISPLAY 0.872340 (-6275 5150);
DISPLAY INVISIBLE (-6275 5150);
FORCEPROP 1 LAST PATH I261
J 2
(-5948 5275);
DISPLAY 0.872340 (-5948 5275);
PAINT GREEN (-5948 5275);
DISPLAY INVISIBLE (-5948 5275);
FORCEADD TAP..1
R 2
(-5950 5175);
FORCEPROP 3 LASTPIN (-5900 5175) SIG_NAME M_D_CPU0_SA_DQS_DN<8>
J 0
(-5890 5185);
DISPLAY 0.659574 (-5890 5185);
PAINT MONO (-5890 5185);
DISPLAY INVISIBLE (-5890 5185);
FORCEPROP 1 LASTPIN (-5900 5175) BN 8
J 2
(-5888 5183);
DISPLAY 0.489362 (-5888 5183);
PAINT GREEN (-5888 5183);
FORCEPROP 2 LAST CDS_LIB mstr_standard
J 2
(-5950 5175);
DISPLAY 0.723404 (-5950 5175);
PAINT MONO (-5950 5175);
DISPLAY INVISIBLE (-5950 5175);
FORCEPROP 1 LAST BODY_TYPE PLUMBING
J 2
(-5950 5225);
DISPLAY 0.872340 (-5950 5225);
PAINT GREEN (-5950 5225);
DISPLAY INVISIBLE (-5950 5225);
FORCEPROP 1 LAST HDL_TAP TRUE
J 2
(-6275 5050);
DISPLAY 0.872340 (-6275 5050);
DISPLAY INVISIBLE (-6275 5050);
FORCEPROP 1 LAST PATH I262
J 2
(-5948 5175);
DISPLAY 0.872340 (-5948 5175);
PAINT GREEN (-5948 5175);
DISPLAY INVISIBLE (-5948 5175);
FORCEADD TAP..1
R 2
(-5750 4875);
FORCEPROP 3 LASTPIN (-5700 4875) SIG_NAME M_D_CPU0_SB_DQS_DP<1>
J 0
(-5690 4885);
DISPLAY 0.659574 (-5690 4885);
PAINT MONO (-5690 4885);
DISPLAY INVISIBLE (-5690 4885);
FORCEPROP 1 LASTPIN (-5700 4875) BN 1
J 2
(-5688 4883);
DISPLAY 0.489362 (-5688 4883);
PAINT GREEN (-5688 4883);
FORCEPROP 2 LAST CDS_LIB mstr_standard
J 2
(-5750 4875);
DISPLAY 0.723404 (-5750 4875);
PAINT MONO (-5750 4875);
DISPLAY INVISIBLE (-5750 4875);
FORCEPROP 1 LAST BODY_TYPE PLUMBING
J 2
(-5750 4925);
DISPLAY 0.872340 (-5750 4925);
PAINT GREEN (-5750 4925);
DISPLAY INVISIBLE (-5750 4925);
FORCEPROP 1 LAST HDL_TAP TRUE
J 2
(-6075 4750);
DISPLAY 0.872340 (-6075 4750);
DISPLAY INVISIBLE (-6075 4750);
FORCEPROP 1 LAST PATH I263
J 2
(-5748 4875);
DISPLAY 0.872340 (-5748 4875);
PAINT GREEN (-5748 4875);
DISPLAY INVISIBLE (-5748 4875);
FORCEADD TAP..1
R 2
(-5750 4975);
FORCEPROP 3 LASTPIN (-5700 4975) SIG_NAME M_D_CPU0_SB_DQS_DP<0>
J 0
(-5690 4985);
DISPLAY 0.659574 (-5690 4985);
PAINT MONO (-5690 4985);
DISPLAY INVISIBLE (-5690 4985);
FORCEPROP 1 LASTPIN (-5700 4975) BN 0
J 2
(-5688 4983);
DISPLAY 0.489362 (-5688 4983);
PAINT GREEN (-5688 4983);
FORCEPROP 2 LAST CDS_LIB mstr_standard
J 2
(-5750 4975);
DISPLAY 0.723404 (-5750 4975);
PAINT MONO (-5750 4975);
DISPLAY INVISIBLE (-5750 4975);
FORCEPROP 1 LAST BODY_TYPE PLUMBING
J 2
(-5750 5025);
DISPLAY 0.872340 (-5750 5025);
PAINT GREEN (-5750 5025);
DISPLAY INVISIBLE (-5750 5025);
FORCEPROP 1 LAST HDL_TAP TRUE
J 2
(-6075 4850);
DISPLAY 0.872340 (-6075 4850);
DISPLAY INVISIBLE (-6075 4850);
FORCEPROP 1 LAST PATH I264
J 2
(-5748 4975);
DISPLAY 0.872340 (-5748 4975);
PAINT GREEN (-5748 4975);
DISPLAY INVISIBLE (-5748 4975);
FORCEADD TAP..1
R 2
(-5750 4775);
FORCEPROP 3 LASTPIN (-5700 4775) SIG_NAME M_D_CPU0_SB_DQS_DP<2>
J 0
(-5690 4785);
DISPLAY 0.659574 (-5690 4785);
PAINT MONO (-5690 4785);
DISPLAY INVISIBLE (-5690 4785);
FORCEPROP 1 LASTPIN (-5700 4775) BN 2
J 2
(-5688 4783);
DISPLAY 0.489362 (-5688 4783);
PAINT GREEN (-5688 4783);
FORCEPROP 2 LAST CDS_LIB mstr_standard
J 2
(-5750 4775);
DISPLAY 0.723404 (-5750 4775);
PAINT MONO (-5750 4775);
DISPLAY INVISIBLE (-5750 4775);
FORCEPROP 1 LAST BODY_TYPE PLUMBING
J 2
(-5750 4825);
DISPLAY 0.872340 (-5750 4825);
PAINT GREEN (-5750 4825);
DISPLAY INVISIBLE (-5750 4825);
FORCEPROP 1 LAST HDL_TAP TRUE
J 2
(-6075 4650);
DISPLAY 0.872340 (-6075 4650);
DISPLAY INVISIBLE (-6075 4650);
FORCEPROP 1 LAST PATH I265
J 2
(-5748 4775);
DISPLAY 0.872340 (-5748 4775);
PAINT GREEN (-5748 4775);
DISPLAY INVISIBLE (-5748 4775);
FORCEADD TAP..1
R 2
(-5750 4675);
FORCEPROP 3 LASTPIN (-5700 4675) SIG_NAME M_D_CPU0_SB_DQS_DP<3>
J 0
(-5690 4685);
DISPLAY 0.659574 (-5690 4685);
PAINT MONO (-5690 4685);
DISPLAY INVISIBLE (-5690 4685);
FORCEPROP 1 LASTPIN (-5700 4675) BN 3
J 2
(-5688 4683);
DISPLAY 0.489362 (-5688 4683);
PAINT GREEN (-5688 4683);
FORCEPROP 2 LAST CDS_LIB mstr_standard
J 2
(-5750 4675);
DISPLAY 0.723404 (-5750 4675);
PAINT MONO (-5750 4675);
DISPLAY INVISIBLE (-5750 4675);
FORCEPROP 1 LAST BODY_TYPE PLUMBING
J 2
(-5750 4725);
DISPLAY 0.872340 (-5750 4725);
PAINT GREEN (-5750 4725);
DISPLAY INVISIBLE (-5750 4725);
FORCEPROP 1 LAST HDL_TAP TRUE
J 2
(-6075 4550);
DISPLAY 0.872340 (-6075 4550);
DISPLAY INVISIBLE (-6075 4550);
FORCEPROP 1 LAST PATH I266
J 2
(-5748 4675);
DISPLAY 0.872340 (-5748 4675);
PAINT GREEN (-5748 4675);
DISPLAY INVISIBLE (-5748 4675);
FORCEADD TAP..1
R 2
(-5950 5075);
FORCEPROP 3 LASTPIN (-5900 5075) SIG_NAME M_D_CPU0_SA_DQS_DN<9>
J 0
(-5890 5085);
DISPLAY 0.659574 (-5890 5085);
PAINT MONO (-5890 5085);
DISPLAY INVISIBLE (-5890 5085);
FORCEPROP 1 LASTPIN (-5900 5075) BN 9
J 2
(-5888 5083);
DISPLAY 0.489362 (-5888 5083);
PAINT GREEN (-5888 5083);
FORCEPROP 2 LAST CDS_LIB mstr_standard
J 2
(-5950 5075);
DISPLAY 0.723404 (-5950 5075);
PAINT MONO (-5950 5075);
DISPLAY INVISIBLE (-5950 5075);
FORCEPROP 1 LAST BODY_TYPE PLUMBING
J 2
(-5950 5125);
DISPLAY 0.872340 (-5950 5125);
PAINT GREEN (-5950 5125);
DISPLAY INVISIBLE (-5950 5125);
FORCEPROP 1 LAST HDL_TAP TRUE
J 2
(-6275 4950);
DISPLAY 0.872340 (-6275 4950);
DISPLAY INVISIBLE (-6275 4950);
FORCEPROP 1 LAST PATH I267
J 2
(-5948 5075);
DISPLAY 0.872340 (-5948 5075);
PAINT GREEN (-5948 5075);
DISPLAY INVISIBLE (-5948 5075);
FORCEADD TAP..1
R 2
(-5950 4925);
FORCEPROP 3 LASTPIN (-5900 4925) SIG_NAME M_D_CPU0_SB_DQS_DN<0>
J 0
(-5890 4935);
DISPLAY 0.659574 (-5890 4935);
PAINT MONO (-5890 4935);
DISPLAY INVISIBLE (-5890 4935);
FORCEPROP 1 LASTPIN (-5900 4925) BN 0
J 2
(-5888 4933);
DISPLAY 0.489362 (-5888 4933);
PAINT GREEN (-5888 4933);
FORCEPROP 2 LAST CDS_LIB mstr_standard
J 2
(-5950 4925);
DISPLAY 0.723404 (-5950 4925);
PAINT MONO (-5950 4925);
DISPLAY INVISIBLE (-5950 4925);
FORCEPROP 1 LAST BODY_TYPE PLUMBING
J 2
(-5950 4975);
DISPLAY 0.872340 (-5950 4975);
PAINT GREEN (-5950 4975);
DISPLAY INVISIBLE (-5950 4975);
FORCEPROP 1 LAST HDL_TAP TRUE
J 2
(-6275 4800);
DISPLAY 0.872340 (-6275 4800);
DISPLAY INVISIBLE (-6275 4800);
FORCEPROP 1 LAST PATH I268
J 2
(-5948 4925);
DISPLAY 0.872340 (-5948 4925);
PAINT GREEN (-5948 4925);
DISPLAY INVISIBLE (-5948 4925);
FORCEADD TAP..1
R 2
(-5950 4825);
FORCEPROP 3 LASTPIN (-5900 4825) SIG_NAME M_D_CPU0_SB_DQS_DN<1>
J 0
(-5890 4835);
DISPLAY 0.659574 (-5890 4835);
PAINT MONO (-5890 4835);
DISPLAY INVISIBLE (-5890 4835);
FORCEPROP 1 LASTPIN (-5900 4825) BN 1
J 2
(-5888 4833);
DISPLAY 0.489362 (-5888 4833);
PAINT GREEN (-5888 4833);
FORCEPROP 2 LAST CDS_LIB mstr_standard
J 2
(-5950 4825);
DISPLAY 0.723404 (-5950 4825);
PAINT MONO (-5950 4825);
DISPLAY INVISIBLE (-5950 4825);
FORCEPROP 1 LAST BODY_TYPE PLUMBING
J 2
(-5950 4875);
DISPLAY 0.872340 (-5950 4875);
PAINT GREEN (-5950 4875);
DISPLAY INVISIBLE (-5950 4875);
FORCEPROP 1 LAST HDL_TAP TRUE
J 2
(-6275 4700);
DISPLAY 0.872340 (-6275 4700);
DISPLAY INVISIBLE (-6275 4700);
FORCEPROP 1 LAST PATH I269
J 2
(-5948 4825);
DISPLAY 0.872340 (-5948 4825);
PAINT GREEN (-5948 4825);
DISPLAY INVISIBLE (-5948 4825);
FORCEADD TAP..1
R 2
(-5950 4725);
FORCEPROP 3 LASTPIN (-5900 4725) SIG_NAME M_D_CPU0_SB_DQS_DN<2>
J 0
(-5890 4735);
DISPLAY 0.659574 (-5890 4735);
PAINT MONO (-5890 4735);
DISPLAY INVISIBLE (-5890 4735);
FORCEPROP 1 LASTPIN (-5900 4725) BN 2
J 2
(-5888 4733);
DISPLAY 0.489362 (-5888 4733);
PAINT GREEN (-5888 4733);
FORCEPROP 2 LAST CDS_LIB mstr_standard
J 2
(-5950 4725);
DISPLAY 0.723404 (-5950 4725);
PAINT MONO (-5950 4725);
DISPLAY INVISIBLE (-5950 4725);
FORCEPROP 1 LAST BODY_TYPE PLUMBING
J 2
(-5950 4775);
DISPLAY 0.872340 (-5950 4775);
PAINT GREEN (-5950 4775);
DISPLAY INVISIBLE (-5950 4775);
FORCEPROP 1 LAST HDL_TAP TRUE
J 2
(-6275 4600);
DISPLAY 0.872340 (-6275 4600);
DISPLAY INVISIBLE (-6275 4600);
FORCEPROP 1 LAST PATH I270
J 2
(-5948 4725);
DISPLAY 0.872340 (-5948 4725);
PAINT GREEN (-5948 4725);
DISPLAY INVISIBLE (-5948 4725);
FORCEADD TAP..1
R 2
(-5950 4625);
FORCEPROP 3 LASTPIN (-5900 4625) SIG_NAME M_D_CPU0_SB_DQS_DN<3>
J 0
(-5890 4635);
DISPLAY 0.659574 (-5890 4635);
PAINT MONO (-5890 4635);
DISPLAY INVISIBLE (-5890 4635);
FORCEPROP 1 LASTPIN (-5900 4625) BN 3
J 2
(-5888 4633);
DISPLAY 0.489362 (-5888 4633);
PAINT GREEN (-5888 4633);
FORCEPROP 2 LAST CDS_LIB mstr_standard
J 2
(-5950 4625);
DISPLAY 0.723404 (-5950 4625);
PAINT MONO (-5950 4625);
DISPLAY INVISIBLE (-5950 4625);
FORCEPROP 1 LAST BODY_TYPE PLUMBING
J 2
(-5950 4675);
DISPLAY 0.872340 (-5950 4675);
PAINT GREEN (-5950 4675);
DISPLAY INVISIBLE (-5950 4675);
FORCEPROP 1 LAST HDL_TAP TRUE
J 2
(-6275 4500);
DISPLAY 0.872340 (-6275 4500);
DISPLAY INVISIBLE (-6275 4500);
FORCEPROP 1 LAST PATH I271
J 2
(-5948 4625);
DISPLAY 0.872340 (-5948 4625);
PAINT GREEN (-5948 4625);
DISPLAY INVISIBLE (-5948 4625);
FORCEADD TAP..1
R 2
(-5750 4575);
FORCEPROP 3 LASTPIN (-5700 4575) SIG_NAME M_D_CPU0_SB_DQS_DP<4>
J 0
(-5690 4585);
DISPLAY 0.659574 (-5690 4585);
PAINT MONO (-5690 4585);
DISPLAY INVISIBLE (-5690 4585);
FORCEPROP 1 LASTPIN (-5700 4575) BN 4
J 2
(-5688 4583);
DISPLAY 0.489362 (-5688 4583);
PAINT GREEN (-5688 4583);
FORCEPROP 2 LAST CDS_LIB mstr_standard
J 2
(-5750 4575);
DISPLAY 0.723404 (-5750 4575);
PAINT MONO (-5750 4575);
DISPLAY INVISIBLE (-5750 4575);
FORCEPROP 1 LAST BODY_TYPE PLUMBING
J 2
(-5750 4625);
DISPLAY 0.872340 (-5750 4625);
PAINT GREEN (-5750 4625);
DISPLAY INVISIBLE (-5750 4625);
FORCEPROP 1 LAST HDL_TAP TRUE
J 2
(-6075 4450);
DISPLAY 0.872340 (-6075 4450);
DISPLAY INVISIBLE (-6075 4450);
FORCEPROP 1 LAST PATH I272
J 2
(-5748 4575);
DISPLAY 0.872340 (-5748 4575);
PAINT GREEN (-5748 4575);
DISPLAY INVISIBLE (-5748 4575);
FORCEADD TAP..1
R 2
(-5750 4475);
FORCEPROP 3 LASTPIN (-5700 4475) SIG_NAME M_D_CPU0_SB_DQS_DP<5>
J 0
(-5690 4485);
DISPLAY 0.659574 (-5690 4485);
PAINT MONO (-5690 4485);
DISPLAY INVISIBLE (-5690 4485);
FORCEPROP 1 LASTPIN (-5700 4475) BN 5
J 2
(-5688 4483);
DISPLAY 0.489362 (-5688 4483);
PAINT GREEN (-5688 4483);
FORCEPROP 2 LAST CDS_LIB mstr_standard
J 2
(-5750 4475);
DISPLAY 0.723404 (-5750 4475);
PAINT MONO (-5750 4475);
DISPLAY INVISIBLE (-5750 4475);
FORCEPROP 1 LAST BODY_TYPE PLUMBING
J 2
(-5750 4525);
DISPLAY 0.872340 (-5750 4525);
PAINT GREEN (-5750 4525);
DISPLAY INVISIBLE (-5750 4525);
FORCEPROP 1 LAST HDL_TAP TRUE
J 2
(-6075 4350);
DISPLAY 0.872340 (-6075 4350);
DISPLAY INVISIBLE (-6075 4350);
FORCEPROP 1 LAST PATH I273
J 2
(-5748 4475);
DISPLAY 0.872340 (-5748 4475);
PAINT GREEN (-5748 4475);
DISPLAY INVISIBLE (-5748 4475);
FORCEADD TAP..1
R 2
(-5750 4375);
FORCEPROP 3 LASTPIN (-5700 4375) SIG_NAME M_D_CPU0_SB_DQS_DP<6>
J 0
(-5690 4385);
DISPLAY 0.659574 (-5690 4385);
PAINT MONO (-5690 4385);
DISPLAY INVISIBLE (-5690 4385);
FORCEPROP 1 LASTPIN (-5700 4375) BN 6
J 2
(-5688 4383);
DISPLAY 0.489362 (-5688 4383);
PAINT GREEN (-5688 4383);
FORCEPROP 2 LAST CDS_LIB mstr_standard
J 2
(-5750 4375);
DISPLAY 0.723404 (-5750 4375);
PAINT MONO (-5750 4375);
DISPLAY INVISIBLE (-5750 4375);
FORCEPROP 1 LAST BODY_TYPE PLUMBING
J 2
(-5750 4425);
DISPLAY 0.872340 (-5750 4425);
PAINT GREEN (-5750 4425);
DISPLAY INVISIBLE (-5750 4425);
FORCEPROP 1 LAST HDL_TAP TRUE
J 2
(-6075 4250);
DISPLAY 0.872340 (-6075 4250);
DISPLAY INVISIBLE (-6075 4250);
FORCEPROP 1 LAST PATH I274
J 2
(-5748 4375);
DISPLAY 0.872340 (-5748 4375);
PAINT GREEN (-5748 4375);
DISPLAY INVISIBLE (-5748 4375);
FORCEADD TAP..1
R 2
(-5750 4275);
FORCEPROP 3 LASTPIN (-5700 4275) SIG_NAME M_D_CPU0_SB_DQS_DP<7>
J 0
(-5690 4285);
DISPLAY 0.659574 (-5690 4285);
PAINT MONO (-5690 4285);
DISPLAY INVISIBLE (-5690 4285);
FORCEPROP 1 LASTPIN (-5700 4275) BN 7
J 2
(-5688 4283);
DISPLAY 0.489362 (-5688 4283);
PAINT GREEN (-5688 4283);
FORCEPROP 2 LAST CDS_LIB mstr_standard
J 2
(-5750 4275);
DISPLAY 0.723404 (-5750 4275);
PAINT MONO (-5750 4275);
DISPLAY INVISIBLE (-5750 4275);
FORCEPROP 1 LAST BODY_TYPE PLUMBING
J 2
(-5750 4325);
DISPLAY 0.872340 (-5750 4325);
PAINT GREEN (-5750 4325);
DISPLAY INVISIBLE (-5750 4325);
FORCEPROP 1 LAST HDL_TAP TRUE
J 2
(-6075 4150);
DISPLAY 0.872340 (-6075 4150);
DISPLAY INVISIBLE (-6075 4150);
FORCEPROP 1 LAST PATH I275
J 2
(-5748 4275);
DISPLAY 0.872340 (-5748 4275);
PAINT GREEN (-5748 4275);
DISPLAY INVISIBLE (-5748 4275);
FORCEADD TAP..1
R 2
(-5750 4175);
FORCEPROP 3 LASTPIN (-5700 4175) SIG_NAME M_D_CPU0_SB_DQS_DP<8>
J 0
(-5690 4185);
DISPLAY 0.659574 (-5690 4185);
PAINT MONO (-5690 4185);
DISPLAY INVISIBLE (-5690 4185);
FORCEPROP 1 LASTPIN (-5700 4175) BN 8
J 2
(-5688 4183);
DISPLAY 0.489362 (-5688 4183);
PAINT GREEN (-5688 4183);
FORCEPROP 2 LAST CDS_LIB mstr_standard
J 2
(-5750 4175);
DISPLAY 0.723404 (-5750 4175);
PAINT MONO (-5750 4175);
DISPLAY INVISIBLE (-5750 4175);
FORCEPROP 1 LAST BODY_TYPE PLUMBING
J 2
(-5750 4225);
DISPLAY 0.872340 (-5750 4225);
PAINT GREEN (-5750 4225);
DISPLAY INVISIBLE (-5750 4225);
FORCEPROP 1 LAST HDL_TAP TRUE
J 2
(-6075 4050);
DISPLAY 0.872340 (-6075 4050);
DISPLAY INVISIBLE (-6075 4050);
FORCEPROP 1 LAST PATH I276
J 2
(-5748 4175);
DISPLAY 0.872340 (-5748 4175);
PAINT GREEN (-5748 4175);
DISPLAY INVISIBLE (-5748 4175);
FORCEADD TAP..1
R 2
(-5950 4525);
FORCEPROP 3 LASTPIN (-5900 4525) SIG_NAME M_D_CPU0_SB_DQS_DN<4>
J 0
(-5890 4535);
DISPLAY 0.659574 (-5890 4535);
PAINT MONO (-5890 4535);
DISPLAY INVISIBLE (-5890 4535);
FORCEPROP 1 LASTPIN (-5900 4525) BN 4
J 2
(-5888 4533);
DISPLAY 0.489362 (-5888 4533);
PAINT GREEN (-5888 4533);
FORCEPROP 2 LAST CDS_LIB mstr_standard
J 2
(-5950 4525);
DISPLAY 0.723404 (-5950 4525);
PAINT MONO (-5950 4525);
DISPLAY INVISIBLE (-5950 4525);
FORCEPROP 1 LAST BODY_TYPE PLUMBING
J 2
(-5950 4575);
DISPLAY 0.872340 (-5950 4575);
PAINT GREEN (-5950 4575);
DISPLAY INVISIBLE (-5950 4575);
FORCEPROP 1 LAST HDL_TAP TRUE
J 2
(-6275 4400);
DISPLAY 0.872340 (-6275 4400);
DISPLAY INVISIBLE (-6275 4400);
FORCEPROP 1 LAST PATH I277
J 2
(-5948 4525);
DISPLAY 0.872340 (-5948 4525);
PAINT GREEN (-5948 4525);
DISPLAY INVISIBLE (-5948 4525);
FORCEADD TAP..1
R 2
(-5950 4425);
FORCEPROP 3 LASTPIN (-5900 4425) SIG_NAME M_D_CPU0_SB_DQS_DN<5>
J 0
(-5890 4435);
DISPLAY 0.659574 (-5890 4435);
PAINT MONO (-5890 4435);
DISPLAY INVISIBLE (-5890 4435);
FORCEPROP 1 LASTPIN (-5900 4425) BN 5
J 2
(-5888 4433);
DISPLAY 0.489362 (-5888 4433);
PAINT GREEN (-5888 4433);
FORCEPROP 2 LAST CDS_LIB mstr_standard
J 2
(-5950 4425);
DISPLAY 0.723404 (-5950 4425);
PAINT MONO (-5950 4425);
DISPLAY INVISIBLE (-5950 4425);
FORCEPROP 1 LAST BODY_TYPE PLUMBING
J 2
(-5950 4475);
DISPLAY 0.872340 (-5950 4475);
PAINT GREEN (-5950 4475);
DISPLAY INVISIBLE (-5950 4475);
FORCEPROP 1 LAST HDL_TAP TRUE
J 2
(-6275 4300);
DISPLAY 0.872340 (-6275 4300);
DISPLAY INVISIBLE (-6275 4300);
FORCEPROP 1 LAST PATH I278
J 2
(-5948 4425);
DISPLAY 0.872340 (-5948 4425);
PAINT GREEN (-5948 4425);
DISPLAY INVISIBLE (-5948 4425);
FORCEADD TAP..1
R 2
(-5950 4325);
FORCEPROP 3 LASTPIN (-5900 4325) SIG_NAME M_D_CPU0_SB_DQS_DN<6>
J 0
(-5890 4335);
DISPLAY 0.659574 (-5890 4335);
PAINT MONO (-5890 4335);
DISPLAY INVISIBLE (-5890 4335);
FORCEPROP 1 LASTPIN (-5900 4325) BN 6
J 2
(-5888 4333);
DISPLAY 0.489362 (-5888 4333);
PAINT GREEN (-5888 4333);
FORCEPROP 2 LAST CDS_LIB mstr_standard
J 2
(-5950 4325);
DISPLAY 0.723404 (-5950 4325);
PAINT MONO (-5950 4325);
DISPLAY INVISIBLE (-5950 4325);
FORCEPROP 1 LAST BODY_TYPE PLUMBING
J 2
(-5950 4375);
DISPLAY 0.872340 (-5950 4375);
PAINT GREEN (-5950 4375);
DISPLAY INVISIBLE (-5950 4375);
FORCEPROP 1 LAST HDL_TAP TRUE
J 2
(-6275 4200);
DISPLAY 0.872340 (-6275 4200);
DISPLAY INVISIBLE (-6275 4200);
FORCEPROP 1 LAST PATH I279
J 2
(-5948 4325);
DISPLAY 0.872340 (-5948 4325);
PAINT GREEN (-5948 4325);
DISPLAY INVISIBLE (-5948 4325);
FORCEADD TAP..1
R 2
(-5950 4225);
FORCEPROP 3 LASTPIN (-5900 4225) SIG_NAME M_D_CPU0_SB_DQS_DN<7>
J 0
(-5890 4235);
DISPLAY 0.659574 (-5890 4235);
PAINT MONO (-5890 4235);
DISPLAY INVISIBLE (-5890 4235);
FORCEPROP 1 LASTPIN (-5900 4225) BN 7
J 2
(-5888 4233);
DISPLAY 0.489362 (-5888 4233);
PAINT GREEN (-5888 4233);
FORCEPROP 2 LAST CDS_LIB mstr_standard
J 2
(-5950 4225);
DISPLAY 0.723404 (-5950 4225);
PAINT MONO (-5950 4225);
DISPLAY INVISIBLE (-5950 4225);
FORCEPROP 1 LAST BODY_TYPE PLUMBING
J 2
(-5950 4275);
DISPLAY 0.872340 (-5950 4275);
PAINT GREEN (-5950 4275);
DISPLAY INVISIBLE (-5950 4275);
FORCEPROP 1 LAST HDL_TAP TRUE
J 2
(-6275 4100);
DISPLAY 0.872340 (-6275 4100);
DISPLAY INVISIBLE (-6275 4100);
FORCEPROP 1 LAST PATH I280
J 2
(-5948 4225);
DISPLAY 0.872340 (-5948 4225);
PAINT GREEN (-5948 4225);
DISPLAY INVISIBLE (-5948 4225);
FORCEADD TAP..1
R 2
(-5950 4125);
FORCEPROP 3 LASTPIN (-5900 4125) SIG_NAME M_D_CPU0_SB_DQS_DN<8>
J 0
(-5890 4135);
DISPLAY 0.659574 (-5890 4135);
PAINT MONO (-5890 4135);
DISPLAY INVISIBLE (-5890 4135);
FORCEPROP 1 LASTPIN (-5900 4125) BN 8
J 2
(-5888 4133);
DISPLAY 0.489362 (-5888 4133);
PAINT GREEN (-5888 4133);
FORCEPROP 2 LAST CDS_LIB mstr_standard
J 2
(-5950 4125);
DISPLAY 0.723404 (-5950 4125);
PAINT MONO (-5950 4125);
DISPLAY INVISIBLE (-5950 4125);
FORCEPROP 1 LAST BODY_TYPE PLUMBING
J 2
(-5950 4175);
DISPLAY 0.872340 (-5950 4175);
PAINT GREEN (-5950 4175);
DISPLAY INVISIBLE (-5950 4175);
FORCEPROP 1 LAST HDL_TAP TRUE
J 2
(-6275 4000);
DISPLAY 0.872340 (-6275 4000);
DISPLAY INVISIBLE (-6275 4000);
FORCEPROP 1 LAST PATH I281
J 2
(-5948 4125);
DISPLAY 0.872340 (-5948 4125);
PAINT GREEN (-5948 4125);
DISPLAY INVISIBLE (-5948 4125);
FORCEADD OFFPAGE..3
R 2
(-6650 6000);
FORCEPROP 2 LAST $XR0 89 
J 0
(-6899 6000);
DISPLAY 0.638298 (-6899 6000);
PAINT MONO (-6899 6000);
FORCEPROP 2 LAST CDS_LIB standard
J 0
(-6650 6000);
DISPLAY INVISIBLE (-6650 6000);
FORCEPROP 1 LAST OFFPAGE TRUE
J 2
(-6975 5875);
DISPLAY 0.872340 (-6975 5875);
PAINT GREEN (-6975 5875);
DISPLAY INVISIBLE (-6975 5875);
FORCEPROP 1 LAST COMMENT_BODY TRUE
J 2
(-6600 5900);
DISPLAY 0.872340 (-6600 5900);
PAINT GREEN (-6600 5900);
DISPLAY INVISIBLE (-6600 5900);
FORCEPROP 2 LAST PATH I282
J 0
(-6950 6050);
DISPLAY 1.021277 (-6950 6050);
DISPLAY INVISIBLE (-6950 6050);
FORCEADD OFFPAGE..3
R 2
(-6650 6050);
FORCEPROP 2 LAST $XR0 89 
J 0
(-6899 6050);
DISPLAY 0.638298 (-6899 6050);
PAINT MONO (-6899 6050);
FORCEPROP 2 LAST CDS_LIB standard
J 0
(-6650 6050);
DISPLAY INVISIBLE (-6650 6050);
FORCEPROP 1 LAST OFFPAGE TRUE
J 2
(-6975 5925);
DISPLAY 0.872340 (-6975 5925);
PAINT GREEN (-6975 5925);
DISPLAY INVISIBLE (-6975 5925);
FORCEPROP 1 LAST COMMENT_BODY TRUE
J 2
(-6600 5950);
DISPLAY 0.872340 (-6600 5950);
PAINT GREEN (-6600 5950);
DISPLAY INVISIBLE (-6600 5950);
FORCEPROP 2 LAST PATH I283
J 0
(-6950 6100);
DISPLAY 1.021277 (-6950 6100);
DISPLAY INVISIBLE (-6950 6100);
FORCEADD OFFPAGE..3
R 2
(-6650 4950);
FORCEPROP 2 LAST $XR0 89 
J 0
(-6899 4950);
DISPLAY 0.638298 (-6899 4950);
PAINT MONO (-6899 4950);
FORCEPROP 2 LAST CDS_LIB standard
J 0
(-6650 4950);
DISPLAY INVISIBLE (-6650 4950);
FORCEPROP 1 LAST OFFPAGE TRUE
J 2
(-6975 4825);
DISPLAY 0.872340 (-6975 4825);
PAINT GREEN (-6975 4825);
DISPLAY INVISIBLE (-6975 4825);
FORCEPROP 1 LAST COMMENT_BODY TRUE
J 2
(-6600 4850);
DISPLAY 0.872340 (-6600 4850);
PAINT GREEN (-6600 4850);
DISPLAY INVISIBLE (-6600 4850);
FORCEPROP 2 LAST PATH I284
J 0
(-6950 5000);
DISPLAY 1.021277 (-6950 5000);
DISPLAY INVISIBLE (-6950 5000);
FORCEADD OFFPAGE..3
R 2
(-6650 5000);
FORCEPROP 2 LAST $XR0 89 
J 0
(-6899 5000);
DISPLAY 0.638298 (-6899 5000);
PAINT MONO (-6899 5000);
FORCEPROP 2 LAST CDS_LIB standard
J 0
(-6650 5000);
DISPLAY INVISIBLE (-6650 5000);
FORCEPROP 1 LAST OFFPAGE TRUE
J 2
(-6975 4875);
DISPLAY 0.872340 (-6975 4875);
PAINT GREEN (-6975 4875);
DISPLAY INVISIBLE (-6975 4875);
FORCEPROP 1 LAST COMMENT_BODY TRUE
J 2
(-6600 4900);
DISPLAY 0.872340 (-6600 4900);
PAINT GREEN (-6600 4900);
DISPLAY INVISIBLE (-6600 4900);
FORCEPROP 2 LAST PATH I285
J 0
(-6950 5050);
DISPLAY 1.021277 (-6950 5050);
DISPLAY INVISIBLE (-6950 5050);
FORCEADD TAP..1
R 2
(-5750 4075);
FORCEPROP 3 LASTPIN (-5700 4075) SIG_NAME M_D_CPU0_SB_DQS_DP<9>
J 0
(-5690 4085);
DISPLAY 0.659574 (-5690 4085);
PAINT MONO (-5690 4085);
DISPLAY INVISIBLE (-5690 4085);
FORCEPROP 1 LASTPIN (-5700 4075) BN 9
J 2
(-5688 4083);
DISPLAY 0.489362 (-5688 4083);
PAINT GREEN (-5688 4083);
FORCEPROP 2 LAST CDS_LIB mstr_standard
J 2
(-5750 4075);
DISPLAY 0.723404 (-5750 4075);
PAINT MONO (-5750 4075);
DISPLAY INVISIBLE (-5750 4075);
FORCEPROP 1 LAST BODY_TYPE PLUMBING
J 2
(-5750 4125);
DISPLAY 0.872340 (-5750 4125);
PAINT GREEN (-5750 4125);
DISPLAY INVISIBLE (-5750 4125);
FORCEPROP 1 LAST HDL_TAP TRUE
J 2
(-6075 3950);
DISPLAY 0.872340 (-6075 3950);
DISPLAY INVISIBLE (-6075 3950);
FORCEPROP 1 LAST PATH I286
J 2
(-5748 4075);
DISPLAY 0.872340 (-5748 4075);
PAINT GREEN (-5748 4075);
DISPLAY INVISIBLE (-5748 4075);
FORCEADD TAP..1
R 2
(-5950 3825);
FORCEPROP 3 LASTPIN (-5900 3825) SIG_NAME M_D_CPU0_SA_CA<1>
J 0
(-5890 3835);
DISPLAY 0.659574 (-5890 3835);
PAINT MONO (-5890 3835);
DISPLAY INVISIBLE (-5890 3835);
FORCEPROP 1 LASTPIN (-5900 3825) BN 1
J 2
(-5888 3833);
DISPLAY 0.489362 (-5888 3833);
PAINT GREEN (-5888 3833);
FORCEPROP 2 LAST CDS_LIB mstr_standard
J 0
(-5950 3825);
DISPLAY 0.723404 (-5950 3825);
PAINT MONO (-5950 3825);
DISPLAY INVISIBLE (-5950 3825);
FORCEPROP 1 LAST BODY_TYPE PLUMBING
J 2
(-5950 3875);
DISPLAY 0.872340 (-5950 3875);
PAINT GREEN (-5950 3875);
DISPLAY INVISIBLE (-5950 3875);
FORCEPROP 1 LAST HDL_TAP TRUE
J 2
(-6275 3700);
DISPLAY 0.872340 (-6275 3700);
DISPLAY INVISIBLE (-6275 3700);
FORCEPROP 1 LAST PATH I287
J 2
(-5948 3825);
DISPLAY 0.872340 (-5948 3825);
PAINT GREEN (-5948 3825);
DISPLAY INVISIBLE (-5948 3825);
FORCEADD TAP..1
R 2
(-5950 4025);
FORCEPROP 3 LASTPIN (-5900 4025) SIG_NAME M_D_CPU0_SB_DQS_DN<9>
J 0
(-5890 4035);
DISPLAY 0.659574 (-5890 4035);
PAINT MONO (-5890 4035);
DISPLAY INVISIBLE (-5890 4035);
FORCEPROP 1 LASTPIN (-5900 4025) BN 9
J 2
(-5888 4033);
DISPLAY 0.489362 (-5888 4033);
PAINT GREEN (-5888 4033);
FORCEPROP 2 LAST CDS_LIB mstr_standard
J 2
(-5950 4025);
DISPLAY 0.723404 (-5950 4025);
PAINT MONO (-5950 4025);
DISPLAY INVISIBLE (-5950 4025);
FORCEPROP 1 LAST BODY_TYPE PLUMBING
J 2
(-5950 4075);
DISPLAY 0.872340 (-5950 4075);
PAINT GREEN (-5950 4075);
DISPLAY INVISIBLE (-5950 4075);
FORCEPROP 1 LAST HDL_TAP TRUE
J 2
(-6275 3900);
DISPLAY 0.872340 (-6275 3900);
DISPLAY INVISIBLE (-6275 3900);
FORCEPROP 1 LAST PATH I288
J 2
(-5948 4025);
DISPLAY 0.872340 (-5948 4025);
PAINT GREEN (-5948 4025);
DISPLAY INVISIBLE (-5948 4025);
FORCEADD TAP..1
R 2
(-5950 3875);
FORCEPROP 3 LASTPIN (-5900 3875) SIG_NAME M_D_CPU0_SA_CA<0>
J 0
(-5890 3885);
DISPLAY 0.659574 (-5890 3885);
PAINT MONO (-5890 3885);
DISPLAY INVISIBLE (-5890 3885);
FORCEPROP 1 LASTPIN (-5900 3875) BN 0
J 2
(-5888 3883);
DISPLAY 0.489362 (-5888 3883);
PAINT GREEN (-5888 3883);
FORCEPROP 2 LAST CDS_LIB mstr_standard
J 0
(-5950 3875);
DISPLAY 0.723404 (-5950 3875);
PAINT MONO (-5950 3875);
DISPLAY INVISIBLE (-5950 3875);
FORCEPROP 1 LAST BODY_TYPE PLUMBING
J 2
(-5950 3925);
DISPLAY 0.872340 (-5950 3925);
PAINT GREEN (-5950 3925);
DISPLAY INVISIBLE (-5950 3925);
FORCEPROP 1 LAST HDL_TAP TRUE
J 2
(-6275 3750);
DISPLAY 0.872340 (-6275 3750);
DISPLAY INVISIBLE (-6275 3750);
FORCEPROP 1 LAST PATH I289
J 2
(-5948 3875);
DISPLAY 0.872340 (-5948 3875);
PAINT GREEN (-5948 3875);
DISPLAY INVISIBLE (-5948 3875);
FORCEADD TAP..1
R 2
(-5950 3775);
FORCEPROP 3 LASTPIN (-5900 3775) SIG_NAME M_D_CPU0_SA_CA<2>
J 0
(-5890 3785);
DISPLAY 0.659574 (-5890 3785);
PAINT MONO (-5890 3785);
DISPLAY INVISIBLE (-5890 3785);
FORCEPROP 1 LASTPIN (-5900 3775) BN 2
J 2
(-5888 3783);
DISPLAY 0.489362 (-5888 3783);
PAINT GREEN (-5888 3783);
FORCEPROP 2 LAST CDS_LIB mstr_standard
J 0
(-5950 3775);
DISPLAY 0.723404 (-5950 3775);
PAINT MONO (-5950 3775);
DISPLAY INVISIBLE (-5950 3775);
FORCEPROP 1 LAST BODY_TYPE PLUMBING
J 2
(-5950 3825);
DISPLAY 0.872340 (-5950 3825);
PAINT GREEN (-5950 3825);
DISPLAY INVISIBLE (-5950 3825);
FORCEPROP 1 LAST HDL_TAP TRUE
J 2
(-6275 3650);
DISPLAY 0.872340 (-6275 3650);
DISPLAY INVISIBLE (-6275 3650);
FORCEPROP 1 LAST PATH I290
J 2
(-5948 3775);
DISPLAY 0.872340 (-5948 3775);
PAINT GREEN (-5948 3775);
DISPLAY INVISIBLE (-5948 3775);
FORCEADD TAP..1
R 2
(-5950 3725);
FORCEPROP 3 LASTPIN (-5900 3725) SIG_NAME M_D_CPU0_SA_CA<3>
J 0
(-5890 3735);
DISPLAY 0.659574 (-5890 3735);
PAINT MONO (-5890 3735);
DISPLAY INVISIBLE (-5890 3735);
FORCEPROP 1 LASTPIN (-5900 3725) BN 3
J 2
(-5888 3733);
DISPLAY 0.489362 (-5888 3733);
PAINT GREEN (-5888 3733);
FORCEPROP 2 LAST CDS_LIB mstr_standard
J 0
(-5950 3725);
DISPLAY 0.723404 (-5950 3725);
PAINT MONO (-5950 3725);
DISPLAY INVISIBLE (-5950 3725);
FORCEPROP 1 LAST BODY_TYPE PLUMBING
J 2
(-5950 3775);
DISPLAY 0.872340 (-5950 3775);
PAINT GREEN (-5950 3775);
DISPLAY INVISIBLE (-5950 3775);
FORCEPROP 1 LAST HDL_TAP TRUE
J 2
(-6275 3600);
DISPLAY 0.872340 (-6275 3600);
DISPLAY INVISIBLE (-6275 3600);
FORCEPROP 1 LAST PATH I291
J 2
(-5948 3725);
DISPLAY 0.872340 (-5948 3725);
PAINT GREEN (-5948 3725);
DISPLAY INVISIBLE (-5948 3725);
FORCEADD TAP..1
R 2
(-5950 3675);
FORCEPROP 3 LASTPIN (-5900 3675) SIG_NAME M_D_CPU0_SA_CA<4>
J 0
(-5890 3685);
DISPLAY 0.659574 (-5890 3685);
PAINT MONO (-5890 3685);
DISPLAY INVISIBLE (-5890 3685);
FORCEPROP 1 LASTPIN (-5900 3675) BN 4
J 2
(-5888 3683);
DISPLAY 0.489362 (-5888 3683);
PAINT GREEN (-5888 3683);
FORCEPROP 2 LAST CDS_LIB mstr_standard
J 0
(-5950 3675);
DISPLAY 0.723404 (-5950 3675);
PAINT MONO (-5950 3675);
DISPLAY INVISIBLE (-5950 3675);
FORCEPROP 1 LAST BODY_TYPE PLUMBING
J 2
(-5950 3725);
DISPLAY 0.872340 (-5950 3725);
PAINT GREEN (-5950 3725);
DISPLAY INVISIBLE (-5950 3725);
FORCEPROP 1 LAST HDL_TAP TRUE
J 2
(-6275 3550);
DISPLAY 0.872340 (-6275 3550);
DISPLAY INVISIBLE (-6275 3550);
FORCEPROP 1 LAST PATH I292
J 2
(-5948 3675);
DISPLAY 0.872340 (-5948 3675);
PAINT GREEN (-5948 3675);
DISPLAY INVISIBLE (-5948 3675);
FORCEADD TAP..1
R 2
(-5950 3625);
FORCEPROP 3 LASTPIN (-5900 3625) SIG_NAME M_D_CPU0_SA_CA<5>
J 0
(-5890 3635);
DISPLAY 0.659574 (-5890 3635);
PAINT MONO (-5890 3635);
DISPLAY INVISIBLE (-5890 3635);
FORCEPROP 1 LASTPIN (-5900 3625) BN 5
J 2
(-5888 3633);
DISPLAY 0.489362 (-5888 3633);
PAINT GREEN (-5888 3633);
FORCEPROP 2 LAST CDS_LIB mstr_standard
J 0
(-5950 3625);
DISPLAY 0.723404 (-5950 3625);
PAINT MONO (-5950 3625);
DISPLAY INVISIBLE (-5950 3625);
FORCEPROP 1 LAST BODY_TYPE PLUMBING
J 2
(-5950 3675);
DISPLAY 0.872340 (-5950 3675);
PAINT GREEN (-5950 3675);
DISPLAY INVISIBLE (-5950 3675);
FORCEPROP 1 LAST HDL_TAP TRUE
J 2
(-6275 3500);
DISPLAY 0.872340 (-6275 3500);
DISPLAY INVISIBLE (-6275 3500);
FORCEPROP 1 LAST PATH I293
J 2
(-5948 3625);
DISPLAY 0.872340 (-5948 3625);
PAINT GREEN (-5948 3625);
DISPLAY INVISIBLE (-5948 3625);
FORCEADD TAP..1
R 2
(-5950 3575);
FORCEPROP 3 LASTPIN (-5900 3575) SIG_NAME M_D_CPU0_SA_CA<6>
J 0
(-5890 3585);
DISPLAY 0.659574 (-5890 3585);
PAINT MONO (-5890 3585);
DISPLAY INVISIBLE (-5890 3585);
FORCEPROP 1 LASTPIN (-5900 3575) BN 6
J 2
(-5888 3583);
DISPLAY 0.489362 (-5888 3583);
PAINT GREEN (-5888 3583);
FORCEPROP 2 LAST CDS_LIB mstr_standard
J 0
(-5950 3575);
DISPLAY 0.723404 (-5950 3575);
PAINT MONO (-5950 3575);
DISPLAY INVISIBLE (-5950 3575);
FORCEPROP 1 LAST BODY_TYPE PLUMBING
J 2
(-5950 3625);
DISPLAY 0.872340 (-5950 3625);
PAINT GREEN (-5950 3625);
DISPLAY INVISIBLE (-5950 3625);
FORCEPROP 1 LAST HDL_TAP TRUE
J 2
(-6275 3450);
DISPLAY 0.872340 (-6275 3450);
DISPLAY INVISIBLE (-6275 3450);
FORCEPROP 1 LAST PATH I294
J 2
(-5948 3575);
DISPLAY 0.872340 (-5948 3575);
PAINT GREEN (-5948 3575);
DISPLAY INVISIBLE (-5948 3575);
FORCEADD TAP..1
R 2
(-5950 3425);
FORCEPROP 3 LASTPIN (-5900 3425) SIG_NAME M_D_CPU0_SB_CA<1>
J 0
(-5890 3435);
DISPLAY 0.659574 (-5890 3435);
PAINT MONO (-5890 3435);
DISPLAY INVISIBLE (-5890 3435);
FORCEPROP 1 LASTPIN (-5900 3425) BN 1
J 2
(-5888 3433);
DISPLAY 0.489362 (-5888 3433);
PAINT GREEN (-5888 3433);
FORCEPROP 2 LAST CDS_LIB mstr_standard
J 0
(-5950 3425);
DISPLAY 0.723404 (-5950 3425);
PAINT MONO (-5950 3425);
DISPLAY INVISIBLE (-5950 3425);
FORCEPROP 1 LAST BODY_TYPE PLUMBING
J 2
(-5950 3475);
DISPLAY 0.872340 (-5950 3475);
PAINT GREEN (-5950 3475);
DISPLAY INVISIBLE (-5950 3475);
FORCEPROP 1 LAST HDL_TAP TRUE
J 2
(-6275 3300);
DISPLAY 0.872340 (-6275 3300);
DISPLAY INVISIBLE (-6275 3300);
FORCEPROP 1 LAST PATH I295
J 2
(-5948 3425);
DISPLAY 0.872340 (-5948 3425);
PAINT GREEN (-5948 3425);
DISPLAY INVISIBLE (-5948 3425);
FORCEADD TAP..1
R 2
(-5950 3475);
FORCEPROP 3 LASTPIN (-5900 3475) SIG_NAME M_D_CPU0_SB_CA<0>
J 0
(-5890 3485);
DISPLAY 0.659574 (-5890 3485);
PAINT MONO (-5890 3485);
DISPLAY INVISIBLE (-5890 3485);
FORCEPROP 1 LASTPIN (-5900 3475) BN 0
J 2
(-5888 3483);
DISPLAY 0.489362 (-5888 3483);
PAINT GREEN (-5888 3483);
FORCEPROP 2 LAST CDS_LIB mstr_standard
J 0
(-5950 3475);
DISPLAY 0.723404 (-5950 3475);
PAINT MONO (-5950 3475);
DISPLAY INVISIBLE (-5950 3475);
FORCEPROP 1 LAST BODY_TYPE PLUMBING
J 2
(-5950 3525);
DISPLAY 0.872340 (-5950 3525);
PAINT GREEN (-5950 3525);
DISPLAY INVISIBLE (-5950 3525);
FORCEPROP 1 LAST HDL_TAP TRUE
J 2
(-6275 3350);
DISPLAY 0.872340 (-6275 3350);
DISPLAY INVISIBLE (-6275 3350);
FORCEPROP 1 LAST PATH I296
J 2
(-5948 3475);
DISPLAY 0.872340 (-5948 3475);
PAINT GREEN (-5948 3475);
DISPLAY INVISIBLE (-5948 3475);
FORCEADD TAP..1
R 2
(-5950 3325);
FORCEPROP 3 LASTPIN (-5900 3325) SIG_NAME M_D_CPU0_SB_CA<3>
J 0
(-5890 3335);
DISPLAY 0.659574 (-5890 3335);
PAINT MONO (-5890 3335);
DISPLAY INVISIBLE (-5890 3335);
FORCEPROP 1 LASTPIN (-5900 3325) BN 3
J 2
(-5888 3333);
DISPLAY 0.489362 (-5888 3333);
PAINT GREEN (-5888 3333);
FORCEPROP 2 LAST CDS_LIB mstr_standard
J 0
(-5950 3325);
DISPLAY 0.723404 (-5950 3325);
PAINT MONO (-5950 3325);
DISPLAY INVISIBLE (-5950 3325);
FORCEPROP 1 LAST BODY_TYPE PLUMBING
J 2
(-5950 3375);
DISPLAY 0.872340 (-5950 3375);
PAINT GREEN (-5950 3375);
DISPLAY INVISIBLE (-5950 3375);
FORCEPROP 1 LAST HDL_TAP TRUE
J 2
(-6275 3200);
DISPLAY 0.872340 (-6275 3200);
DISPLAY INVISIBLE (-6275 3200);
FORCEPROP 1 LAST PATH I297
J 2
(-5948 3325);
DISPLAY 0.872340 (-5948 3325);
PAINT GREEN (-5948 3325);
DISPLAY INVISIBLE (-5948 3325);
FORCEADD TAP..1
R 2
(-5950 3375);
FORCEPROP 3 LASTPIN (-5900 3375) SIG_NAME M_D_CPU0_SB_CA<2>
J 0
(-5890 3385);
DISPLAY 0.659574 (-5890 3385);
PAINT MONO (-5890 3385);
DISPLAY INVISIBLE (-5890 3385);
FORCEPROP 1 LASTPIN (-5900 3375) BN 2
J 2
(-5888 3383);
DISPLAY 0.489362 (-5888 3383);
PAINT GREEN (-5888 3383);
FORCEPROP 2 LAST CDS_LIB mstr_standard
J 0
(-5950 3375);
DISPLAY 0.723404 (-5950 3375);
PAINT MONO (-5950 3375);
DISPLAY INVISIBLE (-5950 3375);
FORCEPROP 1 LAST BODY_TYPE PLUMBING
J 2
(-5950 3425);
DISPLAY 0.872340 (-5950 3425);
PAINT GREEN (-5950 3425);
DISPLAY INVISIBLE (-5950 3425);
FORCEPROP 1 LAST HDL_TAP TRUE
J 2
(-6275 3250);
DISPLAY 0.872340 (-6275 3250);
DISPLAY INVISIBLE (-6275 3250);
FORCEPROP 1 LAST PATH I298
J 2
(-5948 3375);
DISPLAY 0.872340 (-5948 3375);
PAINT GREEN (-5948 3375);
DISPLAY INVISIBLE (-5948 3375);
FORCEADD TAP..1
R 2
(-5950 3275);
FORCEPROP 3 LASTPIN (-5900 3275) SIG_NAME M_D_CPU0_SB_CA<4>
J 0
(-5890 3285);
DISPLAY 0.659574 (-5890 3285);
PAINT MONO (-5890 3285);
DISPLAY INVISIBLE (-5890 3285);
FORCEPROP 1 LASTPIN (-5900 3275) BN 4
J 2
(-5888 3283);
DISPLAY 0.489362 (-5888 3283);
PAINT GREEN (-5888 3283);
FORCEPROP 2 LAST CDS_LIB mstr_standard
J 0
(-5950 3275);
DISPLAY 0.723404 (-5950 3275);
PAINT MONO (-5950 3275);
DISPLAY INVISIBLE (-5950 3275);
FORCEPROP 1 LAST BODY_TYPE PLUMBING
J 2
(-5950 3325);
DISPLAY 0.872340 (-5950 3325);
PAINT GREEN (-5950 3325);
DISPLAY INVISIBLE (-5950 3325);
FORCEPROP 1 LAST HDL_TAP TRUE
J 2
(-6275 3150);
DISPLAY 0.872340 (-6275 3150);
DISPLAY INVISIBLE (-6275 3150);
FORCEPROP 1 LAST PATH I299
J 2
(-5948 3275);
DISPLAY 0.872340 (-5948 3275);
PAINT GREEN (-5948 3275);
DISPLAY INVISIBLE (-5948 3275);
FORCEADD TAP..1
R 2
(-5950 3225);
FORCEPROP 3 LASTPIN (-5900 3225) SIG_NAME M_D_CPU0_SB_CA<5>
J 0
(-5890 3235);
DISPLAY 0.659574 (-5890 3235);
PAINT MONO (-5890 3235);
DISPLAY INVISIBLE (-5890 3235);
FORCEPROP 1 LASTPIN (-5900 3225) BN 5
J 2
(-5888 3233);
DISPLAY 0.489362 (-5888 3233);
PAINT GREEN (-5888 3233);
FORCEPROP 2 LAST CDS_LIB mstr_standard
J 0
(-5950 3225);
DISPLAY 0.723404 (-5950 3225);
PAINT MONO (-5950 3225);
DISPLAY INVISIBLE (-5950 3225);
FORCEPROP 1 LAST BODY_TYPE PLUMBING
J 2
(-5950 3275);
DISPLAY 0.872340 (-5950 3275);
PAINT GREEN (-5950 3275);
DISPLAY INVISIBLE (-5950 3275);
FORCEPROP 1 LAST HDL_TAP TRUE
J 2
(-6275 3100);
DISPLAY 0.872340 (-6275 3100);
DISPLAY INVISIBLE (-6275 3100);
FORCEPROP 1 LAST PATH I300
J 2
(-5948 3225);
DISPLAY 0.872340 (-5948 3225);
PAINT GREEN (-5948 3225);
DISPLAY INVISIBLE (-5948 3225);
FORCEADD TAP..1
R 2
(-5950 3175);
FORCEPROP 3 LASTPIN (-5900 3175) SIG_NAME M_D_CPU0_SB_CA<6>
J 0
(-5890 3185);
DISPLAY 0.659574 (-5890 3185);
PAINT MONO (-5890 3185);
DISPLAY INVISIBLE (-5890 3185);
FORCEPROP 1 LASTPIN (-5900 3175) BN 6
J 2
(-5888 3183);
DISPLAY 0.489362 (-5888 3183);
PAINT GREEN (-5888 3183);
FORCEPROP 2 LAST CDS_LIB mstr_standard
J 0
(-5950 3175);
DISPLAY 0.723404 (-5950 3175);
PAINT MONO (-5950 3175);
DISPLAY INVISIBLE (-5950 3175);
FORCEPROP 1 LAST BODY_TYPE PLUMBING
J 2
(-5950 3225);
DISPLAY 0.872340 (-5950 3225);
PAINT GREEN (-5950 3225);
DISPLAY INVISIBLE (-5950 3225);
FORCEPROP 1 LAST HDL_TAP TRUE
J 2
(-6275 3050);
DISPLAY 0.872340 (-6275 3050);
DISPLAY INVISIBLE (-6275 3050);
FORCEPROP 1 LAST PATH I301
J 2
(-5948 3175);
DISPLAY 0.872340 (-5948 3175);
PAINT GREEN (-5948 3175);
DISPLAY INVISIBLE (-5948 3175);
FORCEADD OFFPAGE..2
R 2
(-6550 3900);
FORCEPROP 2 LAST $XR0 89 
J 0
(-6774 3900);
DISPLAY 0.638298 (-6774 3900);
PAINT MONO (-6774 3900);
FORCEPROP 2 LAST CDS_LIB standard
J 0
(-6550 3900);
DISPLAY INVISIBLE (-6550 3900);
FORCEPROP 1 LAST OFFPAGE TRUE
J 2
(-6875 3775);
DISPLAY 0.872340 (-6875 3775);
PAINT GREEN (-6875 3775);
DISPLAY INVISIBLE (-6875 3775);
FORCEPROP 1 LAST COMMENT_BODY TRUE
J 2
(-6505 3805);
DISPLAY 0.872340 (-6505 3805);
PAINT GREEN (-6505 3805);
DISPLAY INVISIBLE (-6505 3805);
FORCEPROP 2 LAST PATH I302
J 0
(-6825 3950);
DISPLAY 1.021277 (-6825 3950);
DISPLAY INVISIBLE (-6825 3950);
FORCEADD OFFPAGE..2
R 2
(-6550 3500);
FORCEPROP 2 LAST $XR0 89 
J 0
(-6774 3500);
DISPLAY 0.638298 (-6774 3500);
PAINT MONO (-6774 3500);
FORCEPROP 2 LAST CDS_LIB standard
J 0
(-6550 3500);
DISPLAY INVISIBLE (-6550 3500);
FORCEPROP 1 LAST OFFPAGE TRUE
J 2
(-6875 3375);
DISPLAY 0.872340 (-6875 3375);
PAINT GREEN (-6875 3375);
DISPLAY INVISIBLE (-6875 3375);
FORCEPROP 1 LAST COMMENT_BODY TRUE
J 2
(-6505 3405);
DISPLAY 0.872340 (-6505 3405);
PAINT GREEN (-6505 3405);
DISPLAY INVISIBLE (-6505 3405);
FORCEPROP 2 LAST PATH I303
J 0
(-6825 3550);
DISPLAY 1.021277 (-6825 3550);
DISPLAY INVISIBLE (-6825 3550);
FORCEADD OFFPAGE..2
R 2
(-6550 3025);
FORCEPROP 2 LAST $XR0 89 
J 0
(-6774 3025);
DISPLAY 0.638298 (-6774 3025);
PAINT MONO (-6774 3025);
FORCEPROP 2 LAST CDS_LIB standard
J 0
(-6550 3025);
DISPLAY INVISIBLE (-6550 3025);
FORCEPROP 1 LAST OFFPAGE TRUE
J 2
(-6875 2900);
DISPLAY 0.872340 (-6875 2900);
PAINT GREEN (-6875 2900);
DISPLAY INVISIBLE (-6875 2900);
FORCEPROP 1 LAST COMMENT_BODY TRUE
J 2
(-6505 2930);
DISPLAY 0.872340 (-6505 2930);
PAINT GREEN (-6505 2930);
DISPLAY INVISIBLE (-6505 2930);
FORCEPROP 2 LAST PATH I304
J 0
(-6825 3075);
DISPLAY 1.021277 (-6825 3075);
DISPLAY INVISIBLE (-6825 3075);
FORCEADD OFFPAGE..2
R 2
(-6550 2975);
FORCEPROP 2 LAST $XR0 89 
J 0
(-6774 2975);
DISPLAY 0.638298 (-6774 2975);
PAINT MONO (-6774 2975);
FORCEPROP 2 LAST CDS_LIB standard
J 0
(-6550 2975);
DISPLAY INVISIBLE (-6550 2975);
FORCEPROP 1 LAST OFFPAGE TRUE
J 2
(-6875 2850);
DISPLAY 0.872340 (-6875 2850);
PAINT GREEN (-6875 2850);
DISPLAY INVISIBLE (-6875 2850);
FORCEPROP 1 LAST COMMENT_BODY TRUE
J 2
(-6505 2880);
DISPLAY 0.872340 (-6505 2880);
PAINT GREEN (-6505 2880);
DISPLAY INVISIBLE (-6505 2880);
FORCEPROP 2 LAST PATH I305
J 0
(-6825 3025);
DISPLAY 1.021277 (-6825 3025);
DISPLAY INVISIBLE (-6825 3025);
FORCEADD OFFPAGE..2
R 2
(-6550 2875);
FORCEPROP 2 LAST $XR0 89 
J 0
(-6774 2875);
DISPLAY 0.638298 (-6774 2875);
PAINT MONO (-6774 2875);
FORCEPROP 2 LAST CDS_LIB standard
J 0
(-6550 2875);
DISPLAY INVISIBLE (-6550 2875);
FORCEPROP 1 LAST OFFPAGE TRUE
J 2
(-6875 2750);
DISPLAY 0.872340 (-6875 2750);
PAINT GREEN (-6875 2750);
DISPLAY INVISIBLE (-6875 2750);
FORCEPROP 1 LAST COMMENT_BODY TRUE
J 2
(-6505 2780);
DISPLAY 0.872340 (-6505 2780);
PAINT GREEN (-6505 2780);
DISPLAY INVISIBLE (-6505 2780);
FORCEPROP 2 LAST PATH I306
J 0
(-6825 2925);
DISPLAY 1.021277 (-6825 2925);
DISPLAY INVISIBLE (-6825 2925);
FORCEADD OFFPAGE..2
R 2
(-6550 2825);
FORCEPROP 2 LAST $XR0 89 
J 0
(-6774 2825);
DISPLAY 0.638298 (-6774 2825);
PAINT MONO (-6774 2825);
FORCEPROP 2 LAST CDS_LIB standard
J 0
(-6550 2825);
DISPLAY INVISIBLE (-6550 2825);
FORCEPROP 1 LAST OFFPAGE TRUE
J 2
(-6875 2700);
DISPLAY 0.872340 (-6875 2700);
PAINT GREEN (-6875 2700);
DISPLAY INVISIBLE (-6875 2700);
FORCEPROP 1 LAST COMMENT_BODY TRUE
J 2
(-6505 2730);
DISPLAY 0.872340 (-6505 2730);
PAINT GREEN (-6505 2730);
DISPLAY INVISIBLE (-6505 2730);
FORCEPROP 2 LAST PATH I307
J 0
(-6825 2875);
DISPLAY 1.021277 (-6825 2875);
DISPLAY INVISIBLE (-6825 2875);
FORCEADD OFFPAGE..1
(-6550 2725);
FORCEPROP 2 LAST $XR0 89 
J 0
(-6801 2725);
DISPLAY 0.638298 (-6801 2725);
PAINT MONO (-6801 2725);
FORCEPROP 2 LAST CDS_LIB standard
J 0
(-6550 2725);
DISPLAY INVISIBLE (-6550 2725);
FORCEPROP 1 LAST OFFPAGE TRUE
J 0
(-6225 2600);
DISPLAY 0.872340 (-6225 2600);
PAINT GREEN (-6225 2600);
DISPLAY INVISIBLE (-6225 2600);
FORCEPROP 1 LAST COMMENT_BODY TRUE
J 0
(-6425 2625);
DISPLAY 0.872340 (-6425 2625);
PAINT GREEN (-6425 2625);
DISPLAY INVISIBLE (-6425 2625);
FORCEPROP 2 LAST PATH I308
J 0
(-6800 2775);
DISPLAY 1.021277 (-6800 2775);
DISPLAY INVISIBLE (-6800 2775);
FORCEADD OFFPAGE..5
(-6550 2625);
FORCEPROP 2 LAST $XR0 89 
J 0
(-6774 2625);
DISPLAY 0.638298 (-6774 2625);
PAINT MONO (-6774 2625);
FORCEPROP 2 LAST CDS_LIB mstr_standard
J 0
(-6550 2625);
DISPLAY INVISIBLE (-6550 2625);
FORCEPROP 1 LAST OFFPAGE TRUE
J 0
(-6225 2500);
DISPLAY 0.872340 (-6225 2500);
PAINT GREEN (-6225 2500);
DISPLAY INVISIBLE (-6225 2500);
FORCEPROP 1 LAST COMMENT_BODY TRUE
J 0
(-6450 2550);
DISPLAY 0.872340 (-6450 2550);
PAINT GREEN (-6450 2550);
DISPLAY INVISIBLE (-6450 2550);
FORCEPROP 2 LAST PATH I309
J 0
(-6825 2675);
DISPLAY 1.021277 (-6825 2675);
DISPLAY INVISIBLE (-6825 2675);
FORCEADD OFFPAGE..2
R 2
(-6550 2525);
FORCEPROP 2 LAST $XR0 89 
J 0
(-6774 2525);
DISPLAY 0.638298 (-6774 2525);
PAINT MONO (-6774 2525);
FORCEPROP 2 LAST CDS_LIB standard
J 0
(-6550 2525);
DISPLAY INVISIBLE (-6550 2525);
FORCEPROP 1 LAST OFFPAGE TRUE
J 2
(-6875 2400);
DISPLAY 0.872340 (-6875 2400);
PAINT GREEN (-6875 2400);
DISPLAY INVISIBLE (-6875 2400);
FORCEPROP 1 LAST COMMENT_BODY TRUE
J 2
(-6505 2430);
DISPLAY 0.872340 (-6505 2430);
PAINT GREEN (-6505 2430);
DISPLAY INVISIBLE (-6505 2430);
FORCEPROP 2 LAST PATH I310
J 0
(-6825 2575);
DISPLAY 1.021277 (-6825 2575);
DISPLAY INVISIBLE (-6825 2575);
FORCEADD OFFPAGE..2
R 2
(-6550 2475);
FORCEPROP 2 LAST $XR0 89 
J 0
(-6774 2475);
DISPLAY 0.638298 (-6774 2475);
PAINT MONO (-6774 2475);
FORCEPROP 2 LAST CDS_LIB standard
J 0
(-6550 2475);
DISPLAY INVISIBLE (-6550 2475);
FORCEPROP 1 LAST OFFPAGE TRUE
J 2
(-6875 2350);
DISPLAY 0.872340 (-6875 2350);
PAINT GREEN (-6875 2350);
DISPLAY INVISIBLE (-6875 2350);
FORCEPROP 1 LAST COMMENT_BODY TRUE
J 2
(-6505 2380);
DISPLAY 0.872340 (-6505 2380);
PAINT GREEN (-6505 2380);
DISPLAY INVISIBLE (-6505 2380);
FORCEPROP 2 LAST PATH I311
J 0
(-6825 2525);
DISPLAY 1.021277 (-6825 2525);
DISPLAY INVISIBLE (-6825 2525);
FORCEADD OFFPAGE..1
(-6550 2375);
FORCEPROP 2 LAST $XR0 89 
J 0
(-6801 2375);
DISPLAY 0.638298 (-6801 2375);
PAINT MONO (-6801 2375);
FORCEPROP 2 LAST CDS_LIB standard
J 0
(-6550 2375);
DISPLAY INVISIBLE (-6550 2375);
FORCEPROP 1 LAST OFFPAGE TRUE
J 0
(-6225 2250);
DISPLAY 0.872340 (-6225 2250);
PAINT GREEN (-6225 2250);
DISPLAY INVISIBLE (-6225 2250);
FORCEPROP 1 LAST COMMENT_BODY TRUE
J 0
(-6425 2275);
DISPLAY 0.872340 (-6425 2275);
PAINT GREEN (-6425 2275);
DISPLAY INVISIBLE (-6425 2275);
FORCEPROP 2 LAST PATH I312
J 0
(-6800 2425);
DISPLAY 1.021277 (-6800 2425);
DISPLAY INVISIBLE (-6800 2425);
FORCEADD OFFPAGE..5
(-6550 2275);
FORCEPROP 2 LAST $XR0 89 
J 0
(-6774 2275);
DISPLAY 0.638298 (-6774 2275);
PAINT MONO (-6774 2275);
FORCEPROP 2 LAST CDS_LIB standard
J 0
(-6550 2275);
DISPLAY INVISIBLE (-6550 2275);
FORCEPROP 1 LAST OFFPAGE TRUE
J 0
(-6225 2150);
DISPLAY 0.872340 (-6225 2150);
PAINT GREEN (-6225 2150);
DISPLAY INVISIBLE (-6225 2150);
FORCEPROP 1 LAST COMMENT_BODY TRUE
J 0
(-6450 2200);
DISPLAY 0.872340 (-6450 2200);
PAINT GREEN (-6450 2200);
DISPLAY INVISIBLE (-6450 2200);
FORCEPROP 2 LAST PATH I313
J 0
(-6825 2325);
DISPLAY 1.021277 (-6825 2325);
DISPLAY INVISIBLE (-6825 2325);
FORCEADD Q_RES..1
(-6875 2175);
FORCEPROP 1 LAST LOCATION R378
J 0
(-7200 2175);
DISPLAY 0.489362 (-7200 2175);
PAINT SKYBLUE (-7200 2175);
FORCEPROP 0 LAST $SEC 1
J 0
(-7050 2225);
DISPLAY 0.680851 (-7050 2225);
PAINT MONO (-7050 2225);
DISPLAY INVISIBLE (-7050 2225);
FORCEPROP 0 LAST CDS_SEC 1
J 0
(-7050 2225);
DISPLAY 1.021277 (-7050 2225);
DISPLAY INVISIBLE (-7050 2225);
FORCEPROP 1 LASTPIN (-6975 2175) $PN 1
J 0
(-6963 2187);
DISPLAY 0.489362 (-6963 2187);
PAINT MONO (-6963 2187);
FORCEPROP 1 LASTPIN (-6775 2175) $PN 2
J 0
(-6813 2187);
DISPLAY 0.489362 (-6813 2187);
PAINT MONO (-6813 2187);
FORCEPROP 1 LAST PACK_TYPE 0402LF
J 0
(-7200 2150);
DISPLAY 0.489362 (-7200 2150);
PAINT SKYBLUE (-7200 2150);
FORCEPROP 1 LAST TOLERANCE 1%
J 0
(-6600 2175);
DISPLAY 0.489362 (-6600 2175);
PAINT SKYBLUE (-6600 2175);
FORCEPROP 1 LAST VALUE 15
J 2
(-6550 2175);
DISPLAY 0.489362 (-6550 2175);
PAINT SKYBLUE (-6550 2175);
FORCEPROP 1 LAST MATERIAL CHIP
J 0
(-7000 2300);
DISPLAY 0.638298 (-7000 2300);
PAINT SKYBLUE (-7000 2300);
DISPLAY INVISIBLE (-7000 2300);
FORCEPROP 1 LAST WATTAGE 1/16W
J 2
(-6650 2300);
DISPLAY 0.638298 (-6650 2300);
PAINT SKYBLUE (-6650 2300);
DISPLAY INVISIBLE (-6650 2300);
FORCEPROP 2 LAST CDS_LIB pure_quanta
J 0
(-6875 2175);
DISPLAY INVISIBLE (-6875 2175);
FORCEPROP 1 LAST PATH I314
J 0
(-6925 2325);
DISPLAY 0.978723 (-6925 2325);
PAINT WHITE (-6925 2325);
DISPLAY INVISIBLE (-6925 2325);
FORCEPROP 1 LAST PART_NUMBER CS01502FB03
J 0
(-6775 2150);
DISPLAY 0.489362 (-6775 2150);
PAINT SKYBLUE (-6775 2150);
DISPLAY INVISIBLE (-6775 2150);
FORCEADD OFFPAGE..1
(-7750 2175);
FORCEPROP 2 LAST $XR0 89 
J 0
(-7971 2175);
DISPLAY 0.638298 (-7971 2175);
PAINT MONO (-7971 2175);
FORCEPROP 2 LAST CDS_LIB mstr_standard
J 0
(-7750 2175);
DISPLAY INVISIBLE (-7750 2175);
FORCEPROP 1 LAST OFFPAGE TRUE
J 0
(-7425 2050);
DISPLAY 0.872340 (-7425 2050);
PAINT GREEN (-7425 2050);
DISPLAY INVISIBLE (-7425 2050);
FORCEPROP 1 LAST COMMENT_BODY TRUE
J 0
(-7625 2075);
DISPLAY 0.872340 (-7625 2075);
PAINT GREEN (-7625 2075);
DISPLAY INVISIBLE (-7625 2075);
FORCEPROP 2 LAST PATH I315
J 0
(-8025 2225);
DISPLAY 1.021277 (-8025 2225);
DISPLAY INVISIBLE (-8025 2225);
FORCEADD OFFPAGE..5
(-6550 2075);
FORCEPROP 2 LAST $XR0 89 
J 0
(-6774 2075);
DISPLAY 0.638298 (-6774 2075);
PAINT MONO (-6774 2075);
FORCEPROP 2 LAST CDS_LIB standard
J 0
(-6550 2075);
DISPLAY INVISIBLE (-6550 2075);
FORCEPROP 1 LAST OFFPAGE TRUE
J 0
(-6225 1950);
DISPLAY 0.872340 (-6225 1950);
PAINT GREEN (-6225 1950);
DISPLAY INVISIBLE (-6225 1950);
FORCEPROP 1 LAST COMMENT_BODY TRUE
J 0
(-6450 2000);
DISPLAY 0.872340 (-6450 2000);
PAINT GREEN (-6450 2000);
DISPLAY INVISIBLE (-6450 2000);
FORCEPROP 2 LAST PATH I316
J 0
(-6825 2125);
DISPLAY 1.021277 (-6825 2125);
DISPLAY INVISIBLE (-6825 2125);
FORCEADD QUANTA_TITLE_BLOCK_C..1
(-100 100);
FORCEPROP 0 LAST CDS_CON_LAST_MODIFIED Thu Sep 14 16:11:49 2023
J 0
(-1985 115);
DISPLAY INVISIBLE (-1985 115);
FORCEPROP 1 LAST CUSTOM_TXT_CDS <CON_LAST_MODIFIED>
J 0
(-1985 115);
DISPLAY 0.978723 (-1985 115);
FORCEPROP 2 LAST CUSTOM_TXT_CDS <XR_PAGE_TITLE>
J 0
(-7990 5350);
DISPLAY 0.638298 (-7990 5350);
PAINT PINK (-7990 5350);
DISPLAY INVISIBLE (-7990 5350);
FORCEPROP 1 LAST CUSTOM_TXT_CDS <NAME_2>
J 0
(-3275 150);
FORCEPROP 1 LAST CUSTOM_TXT_CDS <NAME_1>
J 0
(-3275 275);
FORCEPROP 1 LAST CUSTOM_TXT_CDS <Q_NUMBER>
J 0
(-1503 203);
DISPLAY 1.212766 (-1503 203);
FORCEPROP 1 LAST CUSTOM_TXT_CDS <Q_PROJ>
J 0
(-2482 202);
DISPLAY 1.212766 (-2482 202);
FORCEPROP 1 LAST CUSTOM_TXT_CDS <Q_REV>
J 0
(-284 203);
DISPLAY 1.212766 (-284 203);
FORCEPROP 1 LAST CUSTOM_TXT_CDS <CON_PAGE_NUM> OF <CON_TOTAL_PAGES>
J 0
(-546 118);
DISPLAY 0.978723 (-546 118);
FORCEPROP 1 LAST Q_TITLE CPU0 DDR CHD
J 0
(-9425 150);
DISPLAY 2.446809 (-9425 150);
PAINT GREEN (-9425 150);
FORCEPROP 2 LAST CDS_LIB pure_quanta
J 0
(-100 100);
DISPLAY INVISIBLE (-100 100);
FORCEPROP 1 LAST CDS_LMAN_SYM_OUTLINE -9475,6775,100,-125
J 0
(-100 100);
DISPLAY 0.468085 (-100 100);
PAINT GREEN (-100 100);
DISPLAY INVISIBLE (-100 100);
FORCEPROP 2 LAST PAGE_BORDER TRUE
J 0
(-7990 5350);
DISPLAY 0.638298 (-7990 5350);
PAINT PINK (-7990 5350);
DISPLAY INVISIBLE (-7990 5350);
FORCEPROP 2 LAST CDS_XR_PAGE_TITLE CR-13 : @T6G_MB_LIB.T6G(SCH_1):PAGE13
J 0
(-7990 5350);
DISPLAY 0.638298 (-7990 5350);
PAINT PINK (-7990 5350);
DISPLAY INVISIBLE (-7990 5350);
FORCEPROP 1 LAST Q_DEPT BU9
J 1
(-3863 149);
DISPLAY 1.957447 (-3863 149);
PAINT GREEN (-3863 149);
DISPLAY INVISIBLE (-3863 149);
FORCEPROP 1 LAST COMMENT_BODY TRUE
J 0
(-88 87);
DISPLAY 0.978723 (-88 87);
PAINT GREEN (-88 87);
DISPLAY INVISIBLE (-88 87);
FORCEADD CAD_NOTE..1
(-7700 2475);
FORCEPROP 0 LAST L1 R1952 PLACE CLOSE TO CPU < 25MM
J 0
(-7850 2350);
DISPLAY 0.617021 (-7850 2350);
PAINT WHITE (-7850 2350);
FORCEPROP 2 LAST CDS_LIB pure_quanta_power
J 0
(-7700 2475);
DISPLAY INVISIBLE (-7700 2475);
FORCEPROP 1 LAST COMMENT_BODY TRUE
J 0
(-7675 2575);
DISPLAY 0.574468 (-7675 2575);
PAINT WHITE (-7675 2575);
DISPLAY INVISIBLE (-7675 2575);
WIRE 17 -1 (-5800 4200)(-5800 4100);
WIRE 17 -1 (-5800 4300)(-5800 4200);
WIRE 17 -1 (-5800 4300)(-5800 4400);
WIRE 17 -1 (-5800 4400)(-5800 4500);
WIRE 17 -1 (-5800 4500)(-5800 4600);
WIRE 17 -1 (-5800 4700)(-5800 4600);
WIRE 17 -1 (-5800 4800)(-5800 4700);
WIRE 17 -1 (-5800 4900)(-5800 4800);
WIRE 17 -1 (-5800 5000)(-5800 4900);
WIRE 17 -1 (-5800 5000)(-6600 5000);
FORCEPROP 2 LAST SIG_NAME M_D_CPU0_SB_DQS_DP<9:0>
J 2
(-6035 5010);
DISPLAY 0.489362 (-6035 5010);
WIRE 17 -1 (-6000 3300)(-6000 3350);
WIRE 17 -1 (-6000 3250)(-6000 3300);
WIRE 17 -1 (-6000 3350)(-6000 3400);
WIRE 17 -1 (-6000 3400)(-6000 3450);
WIRE 17 -1 (-6000 3200)(-6000 3250);
WIRE 17 -1 (-6000 3450)(-6000 3500);
WIRE 17 -1 (-6000 3500)(-6500 3500);
FORCEPROP 2 LAST SIG_NAME M_D_CPU0_SB_CA<6:0>
J 0
(-6500 3510);
DISPLAY 0.489362 (-6500 3510);
WIRE 17 -1 (-6000 3600)(-6000 3650);
WIRE 17 -1 (-6000 3650)(-6000 3700);
WIRE 17 -1 (-6000 3700)(-6000 3750);
WIRE 17 -1 (-6000 3750)(-6000 3800);
WIRE 17 -1 (-6000 3800)(-6000 3850);
WIRE 17 -1 (-6000 3850)(-6000 3900);
WIRE 17 -1 (-6000 3900)(-6500 3900);
FORCEPROP 2 LAST SIG_NAME M_D_CPU0_SA_CA<6:0>
J 0
(-6500 3910);
DISPLAY 0.489362 (-6500 3910);
WIRE 17 -1 (-6000 4150)(-6000 4050);
WIRE 17 -1 (-6000 4250)(-6000 4150);
WIRE 17 -1 (-6000 4250)(-6000 4350);
WIRE 17 -1 (-6000 4350)(-6000 4450);
WIRE 17 -1 (-6000 4450)(-6000 4550);
WIRE 17 -1 (-6000 4650)(-6000 4550);
WIRE 17 -1 (-6000 4750)(-6000 4650);
WIRE 17 -1 (-6000 4850)(-6000 4750);
WIRE 17 -1 (-6000 4950)(-6000 4850);
FORCEPROP 2 LAST SIG_NAME M_D_CPU0_SB_DQS_DN<9:0>
J 2
(-6035 4960);
DISPLAY 0.489362 (-6035 4960);
WIRE 17 -1 (-6000 5200)(-6000 5100);
WIRE 17 -1 (-6000 5300)(-6000 5200);
WIRE 17 -1 (-6000 5300)(-6000 5400);
WIRE 17 -1 (-6000 5400)(-6000 5500);
WIRE 17 -1 (-6000 5500)(-6000 5600);
WIRE 17 -1 (-6000 5700)(-6000 5600);
WIRE 17 -1 (-6000 5800)(-6000 5700);
WIRE 17 -1 (-6000 5900)(-6000 5800);
WIRE 17 -1 (-6000 6000)(-6000 5900);
FORCEPROP 2 LAST SIG_NAME M_D_CPU0_SA_DQS_DN<9:0>
J 2
(-6035 6010);
DISPLAY 0.489362 (-6035 6010);
WIRE 17 -1 (-5800 6050)(-5800 5950);
WIRE 17 -1 (-5800 6050)(-6600 6050);
FORCEPROP 2 LAST SIG_NAME M_D_CPU0_SA_DQS_DP<9:0>
J 2
(-6035 6060);
DISPLAY 0.489362 (-6035 6060);
WIRE 17 -1 (-5800 5250)(-5800 5150);
WIRE 17 -1 (-5800 5350)(-5800 5250);
WIRE 17 -1 (-5800 5350)(-5800 5450);
WIRE 17 -1 (-5800 5450)(-5800 5550);
WIRE 17 -1 (-5800 5550)(-5800 5650);
WIRE 17 -1 (-5800 5750)(-5800 5650);
WIRE 17 -1 (-5800 5850)(-5800 5750);
WIRE 17 -1 (-5800 5950)(-5800 5850);
WIRE 17 -1 (-3275 1900)(-3275 1950);
WIRE 17 -1 (-3275 1900)(-3275 1850);
WIRE 17 -1 (-3275 2000)(-3275 1950);
WIRE 17 -1 (-3275 2000)(-3275 2025);
WIRE 17 -1 (-3275 1800)(-3275 1850);
WIRE 17 -1 (-3275 1750)(-3275 1800);
WIRE 17 -1 (-3275 2025)(-2775 2025);
FORCEPROP 2 LAST SIG_NAME M_D_CPU0_SB_CB<7:0>
J 2
(-2775 2035);
DISPLAY 0.489362 (-2775 2035);
WIRE 17 -1 (-3275 1650)(-3275 1700);
WIRE 17 -1 (-3275 1700)(-3275 1750);
WIRE 17 -1 (-3275 3100)(-3275 3050);
WIRE 17 -1 (-3275 3150)(-3275 3100);
WIRE 17 -1 (-3275 3050)(-3275 3000);
WIRE 17 -1 (-3275 3000)(-3275 2900);
WIRE 17 -1 (-3275 3200)(-3275 3150);
WIRE 17 -1 (-3275 3200)(-3275 3250);
WIRE 17 -1 (-3275 2900)(-3275 2850);
WIRE 17 -1 (-3275 2850)(-3275 2800);
WIRE 17 -1 (-3275 3250)(-3275 3300);
WIRE 17 -1 (-3275 3300)(-3275 3350);
WIRE 17 -1 (-3275 2800)(-3275 2750);
WIRE 17 -1 (-3275 2700)(-3275 2750);
WIRE 17 -1 (-3275 3350)(-3275 3450);
WIRE 17 -1 (-3275 3500)(-3275 3450);
WIRE 17 -1 (-3275 2650)(-3275 2700);
WIRE 17 -1 (-3275 2600)(-3275 2650);
WIRE 17 -1 (-3275 3550)(-3275 3500);
WIRE 17 -1 (-3275 3600)(-3275 3550);
WIRE 17 -1 (-3275 2550)(-3275 2600);
WIRE 17 -1 (-3275 3650)(-3275 3600);
WIRE 17 -1 (-3275 3700)(-3275 3650);
WIRE 17 -1 (-3275 3750)(-3275 3700);
WIRE 17 -1 (-3275 3800)(-3275 3750);
WIRE 17 -1 (-3275 3900)(-3275 3800);
WIRE 17 -1 (-3275 3950)(-3275 3900);
WIRE 17 -1 (-3275 4000)(-3275 3950);
WIRE 17 -1 (-3275 4050)(-3275 4000);
WIRE 17 -1 (-3275 4100)(-3275 4050);
WIRE 17 -1 (-3275 4150)(-3275 4100);
WIRE 17 -1 (-3275 4200)(-3275 4150);
WIRE 17 -1 (-3275 4250)(-3275 4200);
WIRE 17 -1 (-3275 4250)(-2650 4250);
FORCEPROP 2 LAST SIG_NAME M_D_CPU0_SB_DQ<31:0>
J 2
(-2710 4260);
DISPLAY 0.489362 (-2710 4260);
WIRE 17 -1 (-3275 2100)(-3275 2150);
WIRE 17 -1 (-3275 2150)(-3275 2200);
WIRE 17 -1 (-3275 2200)(-3275 2250);
WIRE 17 -1 (-3275 2250)(-3275 2300);
WIRE 17 -1 (-3275 2350)(-3275 2300);
WIRE 17 -1 (-3275 2350)(-3275 2400);
WIRE 17 -1 (-3275 2450)(-3275 2400);
WIRE 17 -1 (-3275 2450)(-3275 2475);
WIRE 17 -1 (-3275 2475)(-2775 2475);
FORCEPROP 2 LAST SIG_NAME M_D_CPU0_SA_CB<7:0>
J 2
(-2775 2485);
DISPLAY 0.489362 (-2775 2485);
WIRE 17 -1 (-3275 4450)(-3275 4500);
WIRE 17 -1 (-3275 4400)(-3275 4450);
WIRE 17 -1 (-3275 4500)(-3275 4550);
WIRE 17 -1 (-3275 4600)(-3275 4550);
WIRE 17 -1 (-3275 4350)(-3275 4400);
WIRE 17 -1 (-3275 4650)(-3275 4600);
WIRE 17 -1 (-3275 4700)(-3275 4650);
WIRE 17 -1 (-3275 4800)(-3275 4700);
WIRE 17 -1 (-3275 4850)(-3275 4800);
WIRE 17 -1 (-3275 4900)(-3275 4850);
WIRE 17 -1 (-3275 4950)(-3275 4900);
WIRE 17 -1 (-3275 5000)(-3275 4950);
WIRE 17 -1 (-3275 5000)(-3275 5050);
WIRE 17 -1 (-3275 5050)(-3275 5100);
WIRE 17 -1 (-3275 5100)(-3275 5150);
WIRE 17 -1 (-3275 5150)(-3275 5250);
WIRE 17 -1 (-3275 5300)(-3275 5250);
WIRE 17 -1 (-3275 5350)(-3275 5300);
WIRE 17 -1 (-3275 5400)(-3275 5350);
WIRE 17 -1 (-3275 5450)(-3275 5400);
WIRE 17 -1 (-3275 5500)(-3275 5450);
WIRE 17 -1 (-3275 5550)(-3275 5500);
WIRE 17 -1 (-3275 5600)(-3275 5550);
WIRE 17 -1 (-3275 5700)(-3275 5600);
WIRE 17 -1 (-3275 5750)(-3275 5700);
WIRE 17 -1 (-3275 5800)(-3275 5750);
WIRE 17 -1 (-3275 5850)(-3275 5800);
WIRE 17 -1 (-3275 5900)(-3275 5850);
WIRE 17 -1 (-3275 5950)(-3275 5900);
WIRE 17 -1 (-3275 6000)(-3275 5950);
WIRE 17 -1 (-3275 6050)(-3275 6000);
WIRE 17 -1 (-3275 6050)(-2650 6050);
FORCEPROP 2 LAST SIG_NAME M_D_CPU0_SA_DQ<31:0>
J 2
(-2710 6060);
DISPLAY 0.489362 (-2710 6060);
WIRE 17 -1 (-6000 4950)(-6600 4950);
WIRE 17 -1 (-6000 6000)(-6600 6000);
WIRE 16 -1 (-7700 2175)(-6975 2175);
FORCEPROP 2 LAST SIG_NAME M_D_CPU0_ALERT_N
J 0
(-7660 2185);
DISPLAY 0.489362 (-7660 2185);
WIRE 16 -1 (-6775 2175)(-5400 2175);
FORCEPROP 2 LAST SIG_NAME M_D_CPU0_ALERT_R_N
J 0
(-6485 2185);
DISPLAY 0.489362 (-6485 2185);
FORCEPROP 2 LASTPROP $XRERR UNIQUE?
J 0
(-6725 2185);
DISPLAY 0.638298 (-6725 2185);
PAINT MONO (-6725 2185);
DISPLAY INVISIBLE (-6725 2185);
WIRE 16 -1 (-5900 5775)(-5400 5775);
WIRE 16 -1 (-5700 4275)(-5400 4275);
WIRE 16 -1 (-5900 3225)(-5400 3225);
WIRE 16 -1 (-3800 4625)(-3375 4625);
WIRE 16 -1 (-3800 4525)(-3375 4525);
WIRE 16 -1 (-3800 5025)(-3375 5025);
WIRE 16 -1 (-3800 5075)(-3375 5075);
WIRE 16 -1 (-3800 5125)(-3375 5125);
WIRE 16 -1 (-3800 5225)(-3375 5225);
WIRE 16 -1 (-5700 5925)(-5400 5925);
WIRE 16 -1 (-3800 4875)(-3375 4875);
WIRE 16 -1 (-3800 5875)(-3375 5875);
WIRE 16 -1 (-3800 5825)(-3375 5825);
WIRE 16 -1 (-3800 5775)(-3375 5775);
WIRE 16 -1 (-3800 5725)(-3375 5725);
WIRE 16 -1 (-3800 5675)(-3375 5675);
WIRE 16 -1 (-3800 5575)(-3375 5575);
WIRE 16 -1 (-3800 5525)(-3375 5525);
WIRE 16 -1 (-3800 5475)(-3375 5475);
WIRE 16 -1 (-3800 5425)(-3375 5425);
WIRE 16 -1 (-3800 5375)(-3375 5375);
WIRE 16 -1 (-3800 5325)(-3375 5325);
WIRE 16 -1 (-3800 5275)(-3375 5275);
WIRE 16 -1 (-3800 6025)(-3375 6025);
WIRE 16 -1 (-3800 5975)(-3375 5975);
WIRE 16 -1 (-3800 5925)(-3375 5925);
WIRE 16 -1 (-3800 4125)(-3375 4125);
WIRE 16 -1 (-3800 4425)(-3375 4425);
WIRE 16 -1 (-3800 4975)(-3375 4975);
WIRE 16 -1 (-3800 4375)(-3375 4375);
WIRE 16 -1 (-3800 4325)(-3375 4325);
WIRE 16 -1 (-3800 4925)(-3375 4925);
WIRE 16 -1 (-3800 4825)(-3375 4825);
WIRE 16 -1 (-3800 4775)(-3375 4775);
WIRE 16 -1 (-3800 4675)(-3375 4675);
WIRE 16 -1 (-3800 4575)(-3375 4575);
WIRE 16 -1 (-3800 4225)(-3375 4225);
WIRE 16 -1 (-3800 4175)(-3375 4175);
WIRE 16 -1 (-3800 4475)(-3375 4475);
WIRE 16 -1 (-3800 3575)(-3375 3575);
WIRE 16 -1 (-3800 3525)(-3375 3525);
WIRE 16 -1 (-3800 4075)(-3375 4075);
WIRE 16 -1 (-3800 3475)(-3375 3475);
WIRE 16 -1 (-3800 4025)(-3375 4025);
WIRE 16 -1 (-3800 3425)(-3375 3425);
WIRE 16 -1 (-3800 3975)(-3375 3975);
WIRE 16 -1 (-3800 3325)(-3375 3325);
WIRE 16 -1 (-3800 3925)(-3375 3925);
WIRE 16 -1 (-3800 3275)(-3375 3275);
WIRE 16 -1 (-3800 3875)(-3375 3875);
WIRE 16 -1 (-3800 3225)(-3375 3225);
WIRE 16 -1 (-3800 3775)(-3375 3775);
WIRE 16 -1 (-3800 3175)(-3375 3175);
WIRE 16 -1 (-3800 3725)(-3375 3725);
WIRE 16 -1 (-3800 3125)(-3375 3125);
WIRE 16 -1 (-3800 3075)(-3375 3075);
WIRE 16 -1 (-3800 3675)(-3375 3675);
WIRE 16 -1 (-3800 3625)(-3375 3625);
WIRE 16 -1 (-3800 2975)(-3375 2975);
WIRE 16 -1 (-3800 2875)(-3375 2875);
WIRE 16 -1 (-3800 2825)(-3375 2825);
WIRE 16 -1 (-3800 2775)(-3375 2775);
WIRE 16 -1 (-3800 2725)(-3375 2725);
WIRE 16 -1 (-3800 2675)(-3375 2675);
WIRE 16 -1 (-3800 2625)(-3375 2625);
WIRE 16 -1 (-3800 2425)(-3375 2425);
WIRE 16 -1 (-3800 2375)(-3375 2375);
WIRE 16 -1 (-3800 2325)(-3375 2325);
WIRE 16 -1 (-3800 2275)(-3375 2275);
WIRE 16 -1 (-3800 2225)(-3375 2225);
WIRE 16 -1 (-3800 2575)(-3375 2575);
WIRE 16 -1 (-3800 2175)(-3375 2175);
WIRE 16 -1 (-3800 2525)(-3375 2525);
WIRE 16 -1 (-3800 2125)(-3375 2125);
WIRE 16 -1 (-3375 2075)(-3800 2075);
WIRE 16 -1 (-3800 3025)(-3375 3025);
WIRE 16 -1 (-3800 1825)(-3375 1825);
WIRE 16 -1 (-3800 1775)(-3375 1775);
WIRE 16 -1 (-3800 1725)(-3375 1725);
WIRE 16 -1 (-3800 1675)(-3375 1675);
WIRE 16 -1 (-3800 1625)(-3375 1625);
WIRE 16 -1 (-3800 1975)(-3375 1975);
WIRE 16 -1 (-3800 1925)(-3375 1925);
WIRE 16 -1 (-3800 1875)(-3375 1875);
WIRE 16 -1 (-5900 5475)(-5400 5475);
WIRE 16 -1 (-5900 5375)(-5400 5375);
WIRE 16 -1 (-5700 5825)(-5400 5825);
WIRE 16 -1 (-5900 5275)(-5400 5275);
WIRE 16 -1 (-5700 5725)(-5400 5725);
WIRE 16 -1 (-5900 5175)(-5400 5175);
WIRE 16 -1 (-5700 5625)(-5400 5625);
WIRE 16 -1 (-5700 5525)(-5400 5525);
WIRE 16 -1 (-5700 5425)(-5400 5425);
WIRE 16 -1 (-5700 5325)(-5400 5325);
WIRE 16 -1 (-5700 5225)(-5400 5225);
WIRE 16 -1 (-5700 5125)(-5400 5125);
WIRE 16 -1 (-5900 5975)(-5400 5975);
WIRE 16 -1 (-5900 5875)(-5400 5875);
WIRE 16 -1 (-5900 5675)(-5400 5675);
WIRE 16 -1 (-5900 5575)(-5400 5575);
WIRE 16 -1 (-5700 6025)(-5400 6025);
WIRE 16 -1 (-5900 4925)(-5400 4925);
WIRE 16 -1 (-5900 4825)(-5400 4825);
WIRE 16 -1 (-5900 4725)(-5400 4725);
WIRE 16 -1 (-5900 4625)(-5400 4625);
WIRE 16 -1 (-5900 5075)(-5400 5075);
WIRE 16 -1 (-5900 4525)(-5400 4525);
WIRE 16 -1 (-5700 4975)(-5400 4975);
WIRE 16 -1 (-5900 4425)(-5400 4425);
WIRE 16 -1 (-5700 4875)(-5400 4875);
WIRE 16 -1 (-5900 4325)(-5400 4325);
WIRE 16 -1 (-5700 4775)(-5400 4775);
WIRE 16 -1 (-5900 4225)(-5400 4225);
WIRE 16 -1 (-5700 4675)(-5400 4675);
WIRE 16 -1 (-5900 4125)(-5400 4125);
WIRE 16 -1 (-5700 4575)(-5400 4575);
WIRE 16 -1 (-5700 4475)(-5400 4475);
WIRE 16 -1 (-5700 4375)(-5400 4375);
WIRE 16 -1 (-5700 4175)(-5400 4175);
WIRE 16 -1 (-5900 3875)(-5400 3875);
WIRE 16 -1 (-5900 3475)(-5400 3475);
WIRE 16 -1 (-5900 3825)(-5400 3825);
WIRE 16 -1 (-5900 3425)(-5400 3425);
WIRE 16 -1 (-5900 3775)(-5400 3775);
WIRE 16 -1 (-5900 3375)(-5400 3375);
WIRE 16 -1 (-5900 3725)(-5400 3725);
WIRE 16 -1 (-5900 4025)(-5400 4025);
WIRE 16 -1 (-5900 3675)(-5400 3675);
WIRE 16 -1 (-5900 3275)(-5400 3275);
WIRE 16 -1 (-5900 3625)(-5400 3625);
WIRE 16 -1 (-5900 3575)(-5400 3575);
WIRE 16 -1 (-5900 3175)(-5400 3175);
WIRE 16 -1 (-5900 3325)(-5400 3325);
WIRE 16 -1 (-5700 4075)(-5400 4075);
WIRE 16 -1 (-6500 2075)(-5400 2075);
FORCEPROP 2 LAST SIG_NAME M_D_CPU0_RESET_N
J 0
(-6500 2085);
DISPLAY 0.489362 (-6500 2085);
WIRE 16 -1 (-6500 2275)(-5400 2275);
FORCEPROP 2 LAST SIG_NAME M_D_CPU0_SB_PAR
J 0
(-6500 2285);
DISPLAY 0.489362 (-6500 2285);
WIRE 16 -1 (-6500 2375)(-5400 2375);
FORCEPROP 2 LAST SIG_NAME M_D_CPU0_SB_RSP<0>
J 0
(-6500 2385);
DISPLAY 0.489362 (-6500 2385);
WIRE 16 -1 (-6500 2475)(-5400 2475);
FORCEPROP 2 LAST SIG_NAME M_D_CPU0_SB_CS_N<1>
J 0
(-6500 2485);
DISPLAY 0.489362 (-6500 2485);
WIRE 16 -1 (-6500 2525)(-5400 2525);
FORCEPROP 2 LAST SIG_NAME M_D_CPU0_SB_CS_N<0>
J 0
(-6500 2535);
DISPLAY 0.489362 (-6500 2535);
WIRE 16 -1 (-6500 2625)(-5400 2625);
FORCEPROP 2 LAST SIG_NAME M_D_CPU0_SA_PAR
J 0
(-6500 2635);
DISPLAY 0.489362 (-6500 2635);
WIRE 16 -1 (-6500 2725)(-5400 2725);
FORCEPROP 2 LAST SIG_NAME M_D_CPU0_SA_RSP<0>
J 0
(-6500 2735);
DISPLAY 0.489362 (-6500 2735);
WIRE 16 -1 (-6500 2825)(-5400 2825);
FORCEPROP 2 LAST SIG_NAME M_D_CPU0_SA_CS_N<1>
J 0
(-6500 2835);
DISPLAY 0.489362 (-6500 2835);
WIRE 16 -1 (-6500 2875)(-5400 2875);
FORCEPROP 2 LAST SIG_NAME M_D_CPU0_SA_CS_N<0>
J 0
(-6500 2885);
DISPLAY 0.489362 (-6500 2885);
WIRE 16 -1 (-6500 2975)(-5400 2975);
FORCEPROP 2 LAST SIG_NAME M_D_CPU0_CLK_DN<0>
J 0
(-6500 2985);
DISPLAY 0.489362 (-6500 2985);
WIRE 16 -1 (-6500 3025)(-5400 3025);
FORCEPROP 2 LAST SIG_NAME M_D_CPU0_CLK_DP<0>
J 0
(-6500 3035);
DISPLAY 0.489362 (-6500 3035);
WIRE 16 -1 (-6500 1225)(-5400 1225);
FORCEPROP 2 LAST SIG_NAME TP_M_D_CPU0_SA_TEST39D
J 0
(-6485 1235);
DISPLAY 0.489362 (-6485 1235);
FORCEPROP 2 LASTPROP $XRERR UNIQUE?
J 0
(-6740 1225);
DISPLAY 0.638298 (-6740 1225);
PAINT MONO (-6740 1225);
DISPLAY INVISIBLE (-6740 1225);
QUIT
